FILE_TYPE = MACRO_DRAWING;
SET COLOR_WIRE YELLOW;
SET COLOR_PROP MONO;
SET COLOR_DOT WHITE;
SET COLOR_ARC YELLOW;
SET COLOR_BODY GREEN;
SET COLOR_NOTE MONO;
SET PROP_DISPLAY VALUE;
SET PAGE_NUMBER P139;
FORCEADD OFFPAGE..4
(-2625 4275);
FORCEPROP 2 LAST $XR0 141 
J 0
(-2439 4275);
DISPLAY 0.638298 (-2439 4275);
PAINT MONO (-2439 4275);
FORCEPROP 1 LAST COMMENT_BODY TRUE
J 0
(-2650 4175);
DISPLAY 0.872340 (-2650 4175);
PAINT GREEN (-2650 4175);
DISPLAY INVISIBLE (-2650 4175);
FORCEPROP 2 LAST CDS_LIB mstr_standard
J 0
(-2625 4275);
PAINT ORANGE (-2625 4275);
DISPLAY INVISIBLE (-2625 4275);
FORCEPROP 2 LAST PATH I101
J 0
(-2425 4350);
DISPLAY 1.021277 (-2425 4350);
PAINT ORANGE (-2425 4350);
DISPLAY INVISIBLE (-2425 4350);
FORCEPROP 1 LAST OFFPAGE TRUE
J 0
(-2300 4150);
DISPLAY 0.872340 (-2300 4150);
PAINT GREEN (-2300 4150);
DISPLAY INVISIBLE (-2300 4150);
FORCEADD OFFPAGE..4
(-2625 4225);
FORCEPROP 2 LAST $XR0 141 
J 0
(-2439 4225);
DISPLAY 0.638298 (-2439 4225);
PAINT MONO (-2439 4225);
FORCEPROP 1 LAST COMMENT_BODY TRUE
J 0
(-2650 4125);
DISPLAY 0.872340 (-2650 4125);
PAINT GREEN (-2650 4125);
DISPLAY INVISIBLE (-2650 4125);
FORCEPROP 2 LAST CDS_LIB mstr_standard
J 0
(-2625 4225);
PAINT ORANGE (-2625 4225);
DISPLAY INVISIBLE (-2625 4225);
FORCEPROP 2 LAST PATH I102
J 0
(-2425 4300);
DISPLAY 1.021277 (-2425 4300);
PAINT ORANGE (-2425 4300);
DISPLAY INVISIBLE (-2425 4300);
FORCEPROP 1 LAST OFFPAGE TRUE
J 0
(-2300 4100);
DISPLAY 0.872340 (-2300 4100);
PAINT GREEN (-2300 4100);
DISPLAY INVISIBLE (-2300 4100);
FORCEADD OFFPAGE..2
(-2625 4175);
FORCEPROP 2 LAST $XR0 141 
J 0
(-2436 4175);
DISPLAY 0.638298 (-2436 4175);
PAINT MONO (-2436 4175);
FORCEPROP 1 LAST OFFPAGE TRUE
J 0
(-2300 4050);
DISPLAY 0.872340 (-2300 4050);
PAINT GREEN (-2300 4050);
DISPLAY INVISIBLE (-2300 4050);
FORCEPROP 1 LAST COMMENT_BODY TRUE
J 0
(-2670 4080);
DISPLAY 0.872340 (-2670 4080);
PAINT GREEN (-2670 4080);
DISPLAY INVISIBLE (-2670 4080);
FORCEPROP 2 LAST CDS_LIB mstr_standard
J 0
(-2625 4175);
PAINT ORANGE (-2625 4175);
DISPLAY INVISIBLE (-2625 4175);
FORCEPROP 2 LAST PATH I103
J 0
(-2425 4250);
DISPLAY 1.021277 (-2425 4250);
PAINT ORANGE (-2425 4250);
DISPLAY INVISIBLE (-2425 4250);
FORCEADD OFFPAGE..2
(-2625 4125);
FORCEPROP 2 LAST $XR0 141 
J 0
(-2436 4125);
DISPLAY 0.638298 (-2436 4125);
PAINT MONO (-2436 4125);
FORCEPROP 1 LAST COMMENT_BODY TRUE
J 0
(-2670 4030);
DISPLAY 0.872340 (-2670 4030);
PAINT GREEN (-2670 4030);
DISPLAY INVISIBLE (-2670 4030);
FORCEPROP 1 LAST OFFPAGE TRUE
J 0
(-2300 4000);
DISPLAY 0.872340 (-2300 4000);
PAINT GREEN (-2300 4000);
DISPLAY INVISIBLE (-2300 4000);
FORCEPROP 2 LAST CDS_LIB mstr_standard
J 0
(-2625 4125);
PAINT ORANGE (-2625 4125);
DISPLAY INVISIBLE (-2625 4125);
FORCEPROP 2 LAST PATH I104
J 0
(-2425 4200);
DISPLAY 1.021277 (-2425 4200);
PAINT ORANGE (-2425 4200);
DISPLAY INVISIBLE (-2425 4200);
FORCEADD OFFPAGE..3
(-2625 4075);
FORCEPROP 2 LAST $XR0 141 
J 0
(-2411 4075);
DISPLAY 0.638298 (-2411 4075);
PAINT MONO (-2411 4075);
FORCEPROP 1 LAST COMMENT_BODY TRUE
J 0
(-2675 3975);
DISPLAY 0.872340 (-2675 3975);
PAINT GREEN (-2675 3975);
DISPLAY INVISIBLE (-2675 3975);
FORCEPROP 1 LAST OFFPAGE TRUE
J 0
(-2300 3950);
DISPLAY 0.872340 (-2300 3950);
PAINT GREEN (-2300 3950);
DISPLAY INVISIBLE (-2300 3950);
FORCEPROP 2 LAST CDS_LIB mstr_standard
J 0
(-2625 4075);
PAINT ORANGE (-2625 4075);
DISPLAY INVISIBLE (-2625 4075);
FORCEPROP 2 LAST PATH I105
J 0
(-2425 4150);
DISPLAY 1.021277 (-2425 4150);
PAINT ORANGE (-2425 4150);
DISPLAY INVISIBLE (-2425 4150);
FORCEADD OFFPAGE..3
(-2625 4025);
FORCEPROP 2 LAST $XR0 141 
J 0
(-2411 4025);
DISPLAY 0.638298 (-2411 4025);
PAINT MONO (-2411 4025);
FORCEPROP 1 LAST COMMENT_BODY TRUE
J 0
(-2675 3925);
DISPLAY 0.872340 (-2675 3925);
PAINT GREEN (-2675 3925);
DISPLAY INVISIBLE (-2675 3925);
FORCEPROP 2 LAST CDS_LIB mstr_standard
J 0
(-2625 4025);
PAINT ORANGE (-2625 4025);
DISPLAY INVISIBLE (-2625 4025);
FORCEPROP 1 LAST OFFPAGE TRUE
J 0
(-2300 3900);
DISPLAY 0.872340 (-2300 3900);
PAINT GREEN (-2300 3900);
DISPLAY INVISIBLE (-2300 3900);
FORCEPROP 2 LAST PATH I106
J 0
(-2425 4100);
DISPLAY 1.021277 (-2425 4100);
PAINT ORANGE (-2425 4100);
DISPLAY INVISIBLE (-2425 4100);
FORCEADD OFFPAGE..3
(-2625 3925);
FORCEPROP 2 LAST $XR0 141 
J 0
(-2411 3925);
DISPLAY 0.638298 (-2411 3925);
PAINT MONO (-2411 3925);
FORCEPROP 1 LAST COMMENT_BODY TRUE
J 0
(-2675 3825);
DISPLAY 0.872340 (-2675 3825);
PAINT GREEN (-2675 3825);
DISPLAY INVISIBLE (-2675 3825);
FORCEPROP 2 LAST CDS_LIB mstr_standard
J 0
(-2625 3925);
PAINT ORANGE (-2625 3925);
DISPLAY INVISIBLE (-2625 3925);
FORCEPROP 2 LAST PATH I107
J 0
(-2425 4000);
DISPLAY 1.021277 (-2425 4000);
PAINT ORANGE (-2425 4000);
DISPLAY INVISIBLE (-2425 4000);
FORCEPROP 1 LAST OFFPAGE TRUE
J 0
(-2300 3800);
DISPLAY 0.872340 (-2300 3800);
PAINT GREEN (-2300 3800);
DISPLAY INVISIBLE (-2300 3800);
FORCEADD OFFPAGE..3
(-2625 3975);
FORCEPROP 2 LAST $XR0 141 
J 0
(-2411 3975);
DISPLAY 0.638298 (-2411 3975);
PAINT MONO (-2411 3975);
FORCEPROP 1 LAST COMMENT_BODY TRUE
J 0
(-2675 3875);
DISPLAY 0.872340 (-2675 3875);
PAINT GREEN (-2675 3875);
DISPLAY INVISIBLE (-2675 3875);
FORCEPROP 2 LAST CDS_LIB mstr_standard
J 0
(-2625 3975);
PAINT ORANGE (-2625 3975);
DISPLAY INVISIBLE (-2625 3975);
FORCEPROP 2 LAST PATH I108
J 0
(-2425 4050);
DISPLAY 1.021277 (-2425 4050);
PAINT ORANGE (-2425 4050);
DISPLAY INVISIBLE (-2425 4050);
FORCEPROP 1 LAST OFFPAGE TRUE
J 0
(-2300 3850);
DISPLAY 0.872340 (-2300 3850);
PAINT GREEN (-2300 3850);
DISPLAY INVISIBLE (-2300 3850);
FORCEADD CRYSTAL..1
(-7525 1475);
FORCEPROP 1 LAST PART_NUMBER D71700-057
J 0
(-7725 1625);
DISPLAY 0.617021 (-7725 1625);
PAINT BLUE (-7725 1625);
FORCEPROP 1 LASTPIN (-7625 1475) $PN 1
J 2
(-7580 1485);
DISPLAY 0.617021 (-7580 1485);
PAINT AQUA (-7580 1485);
FORCEPROP 1 LASTPIN (-7425 1475) $PN 3
J 0
(-7460 1485);
DISPLAY 0.617021 (-7460 1485);
PAINT AQUA (-7460 1485);
FORCEPROP 1 LAST MATERIAL IC
J 0
(-7536 1391);
DISPLAY 0.617021 (-7536 1391);
PAINT SKYBLUE (-7536 1391);
FORCEPROP 1 LAST VALUE 25.000MHZ
J 1
(-7518 1536);
DISPLAY 0.617021 (-7518 1536);
PAINT SKYBLUE (-7518 1536);
FORCEPROP 1 LAST LOCATION Y9E1
J 1
(-7520 1574);
DISPLAY 0.617021 (-7520 1574);
PAINT AQUA (-7520 1574);
FORCEPROP 2 LAST CDS_LIB mstr_discrete
J 0
(-7525 1475);
PAINT ORANGE (-7525 1475);
DISPLAY INVISIBLE (-7525 1475);
FORCEPROP 1 LAST PACK_TYPE 2013
J 0
(-7537 1383);
DISPLAY 0.702128 (-7537 1383);
PAINT SKYBLUE (-7537 1383);
DISPLAY INVISIBLE (-7537 1383);
FORCEPROP 2 LAST ROOM NIC_SPRV
J 0
(-7500 1625);
DISPLAY 1.021277 (-7500 1625);
PAINT ORANGE (-7500 1625);
DISPLAY INVISIBLE (-7500 1625);
FORCEPROP 1 LAST PATH I109
J 0
(-7500 1575);
DISPLAY 0.872340 (-7500 1575);
PAINT PINK (-7500 1575);
DISPLAY INVISIBLE (-7500 1575);
FORCEPROP 2 LAST CDS_LOCATION Y9E1
J 1
(-7520 1574);
DISPLAY 0.617021 (-7520 1574);
PAINT AQUA (-7520 1574);
DISPLAY INVISIBLE (-7520 1574);
FORCEPROP 2 LAST SEC 1
J 0
(-7500 1625);
DISPLAY 0.680851 (-7500 1625);
PAINT MONO (-7500 1625);
DISPLAY INVISIBLE (-7500 1625);
FORCEPROP 2 LAST SEC_TYPE 2013
J 0
(-7500 1625);
DISPLAY 1.021277 (-7500 1625);
PAINT ORANGE (-7500 1625);
DISPLAY INVISIBLE (-7500 1625);
FORCEPROP 2 LAST BOM_COST NT_GBE_BASE
J 0
(-7500 1675);
DISPLAY 1.021277 (-7500 1675);
PAINT ORANGE (-7500 1675);
DISPLAY INVISIBLE (-7500 1675);
FORCEADD RES..1
(-6875 1675);
FORCEPROP 1 LASTPIN (-6975 1675) $PN 1
J 0
(-6963 1687);
DISPLAY 0.617021 (-6963 1687);
PAINT ORANGE (-6963 1687);
FORCEPROP 1 LAST MATERIAL CHIP
J 0
(-7100 1625);
DISPLAY 0.617021 (-7100 1625);
PAINT SKYBLUE (-7100 1625);
FORCEPROP 1 LAST LOCATION R9E20
J 0
(-6925 1725);
DISPLAY 0.617021 (-6925 1725);
PAINT AQUA (-6925 1725);
FORCEPROP 1 LASTPIN (-6775 1675) $PN 2
J 0
(-6813 1687);
DISPLAY 0.617021 (-6813 1687);
PAINT ORANGE (-6813 1687);
FORCEPROP 1 LAST VALUE 0.0
J 2
(-6725 1625);
DISPLAY 0.617021 (-6725 1625);
PAINT SKYBLUE (-6725 1625);
FORCEPROP 1 LAST TOLERANCE 5%
J 0
(-6700 1625);
DISPLAY 0.617021 (-6700 1625);
PAINT SKYBLUE (-6700 1625);
FORCEPROP 1 LAST WATTAGE 1/16W
J 2
(-6900 1525);
DISPLAY 0.978723 (-6900 1525);
PAINT SKYBLUE (-6900 1525);
DISPLAY INVISIBLE (-6900 1525);
FORCEPROP 2 LAST CDS_LOCATION R9E20
J 0
(-6925 1725);
DISPLAY 0.617021 (-6925 1725);
PAINT AQUA (-6925 1725);
DISPLAY INVISIBLE (-6925 1725);
FORCEPROP 1 LAST PART_NUMBER G21497-005
J 0
(-6925 1775);
DISPLAY 0.978723 (-6925 1775);
PAINT BLUE (-6925 1775);
DISPLAY INVISIBLE (-6925 1775);
FORCEPROP 2 LAST ROOM NIC_SPRV
J 0
(-6925 1775);
DISPLAY 1.021277 (-6925 1775);
PAINT ORANGE (-6925 1775);
DISPLAY INVISIBLE (-6925 1775);
FORCEPROP 2 LAST BOM_COST NT_GBE_BASE
J 0
(-6925 1825);
DISPLAY 1.021277 (-6925 1825);
PAINT ORANGE (-6925 1825);
DISPLAY INVISIBLE (-6925 1825);
FORCEPROP 2 LAST SEC_TYPE 0402
J 0
(-6925 1875);
DISPLAY 1.021277 (-6925 1875);
PAINT ORANGE (-6925 1875);
DISPLAY INVISIBLE (-6925 1875);
FORCEPROP 2 LAST SEC 1
J 0
(-6925 1875);
PAINT MONO (-6925 1875);
DISPLAY INVISIBLE (-6925 1875);
FORCEPROP 1 LAST PATH I110
J 0
(-6925 1825);
DISPLAY 0.978723 (-6925 1825);
PAINT WHITE (-6925 1825);
DISPLAY INVISIBLE (-6925 1825);
FORCEPROP 2 LAST CDS_LIB mstr_discrete
J 0
(-6875 1675);
PAINT ORANGE (-6875 1675);
DISPLAY INVISIBLE (-6875 1675);
FORCEPROP 1 LAST PACK_TYPE 0402
J 0
(-6625 1525);
DISPLAY 0.978723 (-6625 1525);
PAINT SKYBLUE (-6625 1525);
DISPLAY INVISIBLE (-6625 1525);
FORCEADD CAP..1
(-7325 1275);
FORCEPROP 1 LASTPIN (-7325 1175) $PN 2
J 0
(-7315 1155);
DISPLAY 0.617021 (-7315 1155);
PAINT ORANGE (-7315 1155);
FORCEPROP 1 LAST MATERIAL COG
J 0
(-7275 1175);
DISPLAY 0.617021 (-7275 1175);
PAINT SKYBLUE (-7275 1175);
FORCEPROP 1 LAST TOLERANCE 5%
J 0
(-7275 1225);
DISPLAY 0.617021 (-7275 1225);
PAINT SKYBLUE (-7275 1225);
FORCEPROP 1 LAST VOLTAGE 50V
J 0
(-7275 1275);
DISPLAY 0.617021 (-7275 1275);
PAINT SKYBLUE (-7275 1275);
FORCEPROP 1 LASTPIN (-7325 1375) $PN 1
J 0
(-7315 1355);
DISPLAY 0.617021 (-7315 1355);
PAINT ORANGE (-7315 1355);
FORCEPROP 1 LAST PACK_TYPE 0402LF
J 0
(-7275 1075);
DISPLAY 0.617021 (-7275 1075);
PAINT SKYBLUE (-7275 1075);
FORCEPROP 1 LAST VALUE 22.0PF
J 0
(-7275 1325);
DISPLAY 0.617021 (-7275 1325);
PAINT SKYBLUE (-7275 1325);
FORCEPROP 1 LAST PART_NUMBER A36095-030
J 0
(-7275 1125);
DISPLAY 0.617021 (-7275 1125);
PAINT BLUE (-7275 1125);
FORCEPROP 1 LAST LOCATION C9E8
J 0
(-7275 1375);
DISPLAY 0.617021 (-7275 1375);
PAINT AQUA (-7275 1375);
FORCEPROP 2 LAST CDS_LIB mstr_discrete
J 0
(-7325 1275);
PAINT ORANGE (-7325 1275);
DISPLAY INVISIBLE (-7325 1275);
FORCEPROP 2 LAST ROOM NIC_SPRV
J 0
(-7275 1425);
DISPLAY 1.021277 (-7275 1425);
PAINT ORANGE (-7275 1425);
DISPLAY INVISIBLE (-7275 1425);
FORCEPROP 1 LAST PATH I111
J 0
(-7275 1425);
DISPLAY 0.978723 (-7275 1425);
PAINT WHITE (-7275 1425);
DISPLAY INVISIBLE (-7275 1425);
FORCEPROP 2 LAST CDS_LOCATION C9E8
J 0
(-7275 1375);
DISPLAY 0.617021 (-7275 1375);
PAINT AQUA (-7275 1375);
DISPLAY INVISIBLE (-7275 1375);
FORCEPROP 2 LAST SEC 1
J 0
(-7275 1475);
PAINT MONO (-7275 1475);
DISPLAY INVISIBLE (-7275 1475);
FORCEPROP 2 LAST BOM_COST NT_GBE_BASE
J 0
(-7275 1475);
DISPLAY 1.021277 (-7275 1475);
PAINT ORANGE (-7275 1475);
DISPLAY INVISIBLE (-7275 1475);
FORCEPROP 2 LAST SEC_TYPE 0402LF
J 0
(-7275 1475);
DISPLAY 1.021277 (-7275 1475);
PAINT ORANGE (-7275 1475);
DISPLAY INVISIBLE (-7275 1475);
FORCEADD CAP..1
(-7750 1275);
FORCEPROP 1 LASTPIN (-7750 1175) $PN 2
J 0
(-7740 1155);
DISPLAY 0.617021 (-7740 1155);
PAINT ORANGE (-7740 1155);
FORCEPROP 1 LASTPIN (-7750 1375) $PN 1
J 0
(-7740 1355);
DISPLAY 0.617021 (-7740 1355);
PAINT ORANGE (-7740 1355);
FORCEPROP 1 LAST MATERIAL COG
J 0
(-7700 1175);
DISPLAY 0.617021 (-7700 1175);
PAINT SKYBLUE (-7700 1175);
FORCEPROP 1 LAST VOLTAGE 50V
J 0
(-7700 1275);
DISPLAY 0.617021 (-7700 1275);
PAINT SKYBLUE (-7700 1275);
FORCEPROP 1 LAST PACK_TYPE 0402LF
J 0
(-7700 1075);
DISPLAY 0.617021 (-7700 1075);
PAINT SKYBLUE (-7700 1075);
FORCEPROP 1 LAST TOLERANCE 5%
J 0
(-7700 1225);
DISPLAY 0.617021 (-7700 1225);
PAINT SKYBLUE (-7700 1225);
FORCEPROP 1 LAST VALUE 22.0PF
J 0
(-7700 1325);
DISPLAY 0.617021 (-7700 1325);
PAINT SKYBLUE (-7700 1325);
FORCEPROP 1 LAST PART_NUMBER A36095-030
J 0
(-7700 1125);
DISPLAY 0.617021 (-7700 1125);
PAINT BLUE (-7700 1125);
FORCEPROP 1 LAST LOCATION C9E9
J 0
(-7700 1375);
DISPLAY 0.617021 (-7700 1375);
PAINT AQUA (-7700 1375);
FORCEPROP 2 LAST CDS_LIB mstr_discrete
J 0
(-7750 1275);
PAINT ORANGE (-7750 1275);
DISPLAY INVISIBLE (-7750 1275);
FORCEPROP 2 LAST CDS_LOCATION C9E9
J 0
(-7700 1375);
DISPLAY 0.617021 (-7700 1375);
PAINT AQUA (-7700 1375);
DISPLAY INVISIBLE (-7700 1375);
FORCEPROP 2 LAST BOM_COST NT_GBE_BASE
J 0
(-7700 1475);
DISPLAY 1.021277 (-7700 1475);
PAINT ORANGE (-7700 1475);
DISPLAY INVISIBLE (-7700 1475);
FORCEPROP 2 LAST SEC_TYPE 0402LF
J 0
(-7700 1475);
DISPLAY 1.021277 (-7700 1475);
PAINT ORANGE (-7700 1475);
DISPLAY INVISIBLE (-7700 1475);
FORCEPROP 2 LAST SEC 1
J 0
(-7700 1475);
PAINT MONO (-7700 1475);
DISPLAY INVISIBLE (-7700 1475);
FORCEPROP 1 LAST PATH I112
J 0
(-7700 1425);
DISPLAY 0.978723 (-7700 1425);
PAINT WHITE (-7700 1425);
DISPLAY INVISIBLE (-7700 1425);
FORCEPROP 2 LAST ROOM NIC_SPRV
J 0
(-7700 1425);
DISPLAY 1.021277 (-7700 1425);
PAINT ORANGE (-7700 1425);
DISPLAY INVISIBLE (-7700 1425);
FORCEADD GND..1
(-7325 925);
FORCEPROP 3 LASTPIN (-7325 975) SIG_NAME GND\g
J 0
(-7315 985);
DISPLAY 0.659574 (-7315 985);
PAINT MONO (-7315 985);
DISPLAY INVISIBLE (-7315 985);
FORCEPROP 1 LAST VOLTAGE 0.0V
J 0
(-7370 882);
DISPLAY 0.340426 (-7370 882);
PAINT SKYBLUE (-7370 882);
DISPLAY INVISIBLE (-7370 882);
FORCEPROP 1 LAST SIZE 1B
J 0
(-7250 875);
DISPLAY 0.872340 (-7250 875);
PAINT AQUA (-7250 875);
DISPLAY INVISIBLE (-7250 875);
FORCEPROP 2 LAST CDS_LIB mstr_symbols
J 0
(-7325 925);
PAINT ORANGE (-7325 925);
DISPLAY INVISIBLE (-7325 925);
FORCEPROP 1 LAST BODY_TYPE PLUMBING
J 0
(-7370 882);
DISPLAY 0.340426 (-7370 882);
PAINT GREEN (-7370 882);
DISPLAY INVISIBLE (-7370 882);
FORCEPROP 1 LAST PATH I113
J 0
(-7250 925);
DISPLAY 0.872340 (-7250 925);
PAINT AQUA (-7250 925);
DISPLAY INVISIBLE (-7250 925);
FORCEPROP 1 LAST HDL_POWER GND
J 0
(-7325 1075);
DISPLAY 0.872340 (-7325 1075);
PAINT GREEN (-7325 1075);
DISPLAY INVISIBLE (-7325 1075);
FORCEADD GND..1
(-7750 925);
FORCEPROP 3 LASTPIN (-7750 975) SIG_NAME GND\g
J 0
(-7740 985);
DISPLAY 0.659574 (-7740 985);
PAINT MONO (-7740 985);
DISPLAY INVISIBLE (-7740 985);
FORCEPROP 1 LAST BODY_TYPE PLUMBING
J 0
(-7795 882);
DISPLAY 0.340426 (-7795 882);
PAINT GREEN (-7795 882);
DISPLAY INVISIBLE (-7795 882);
FORCEPROP 2 LAST CDS_LIB mstr_symbols
J 0
(-7750 925);
PAINT ORANGE (-7750 925);
DISPLAY INVISIBLE (-7750 925);
FORCEPROP 1 LAST VOLTAGE 0.0V
J 0
(-7795 882);
DISPLAY 0.340426 (-7795 882);
PAINT SKYBLUE (-7795 882);
DISPLAY INVISIBLE (-7795 882);
FORCEPROP 1 LAST PATH I114
J 0
(-7675 925);
DISPLAY 0.872340 (-7675 925);
PAINT AQUA (-7675 925);
DISPLAY INVISIBLE (-7675 925);
FORCEPROP 1 LAST SIZE 1B
J 0
(-7675 875);
DISPLAY 0.872340 (-7675 875);
PAINT AQUA (-7675 875);
DISPLAY INVISIBLE (-7675 875);
FORCEPROP 1 LAST HDL_POWER GND
J 0
(-7750 1075);
DISPLAY 0.872340 (-7750 1075);
PAINT GREEN (-7750 1075);
DISPLAY INVISIBLE (-7750 1075);
FORCEADD OFFPAGE..2
(-6350 1675);
FORCEPROP 2 LAST $XR0 139 
J 0
(-6161 1675);
DISPLAY 0.638298 (-6161 1675);
PAINT MONO (-6161 1675);
FORCEPROP 1 LAST COMMENT_BODY TRUE
J 0
(-6395 1580);
DISPLAY 0.872340 (-6395 1580);
PAINT GREEN (-6395 1580);
DISPLAY INVISIBLE (-6395 1580);
FORCEPROP 2 LAST CDS_LIB mstr_standard
J 0
(-6350 1675);
PAINT ORANGE (-6350 1675);
DISPLAY INVISIBLE (-6350 1675);
FORCEPROP 2 LAST PATH I115
J 0
(-6300 1750);
DISPLAY 1.021277 (-6300 1750);
PAINT ORANGE (-6300 1750);
DISPLAY INVISIBLE (-6300 1750);
FORCEPROP 1 LAST OFFPAGE TRUE
J 0
(-6025 1550);
DISPLAY 0.872340 (-6025 1550);
PAINT GREEN (-6025 1550);
DISPLAY INVISIBLE (-6025 1550);
FORCEADD OFFPAGE..4
(-6350 1575);
FORCEPROP 2 LAST $XR0 139 
J 0
(-6164 1575);
DISPLAY 0.638298 (-6164 1575);
PAINT MONO (-6164 1575);
FORCEPROP 1 LAST COMMENT_BODY TRUE
J 0
(-6375 1475);
DISPLAY 0.872340 (-6375 1475);
PAINT GREEN (-6375 1475);
DISPLAY INVISIBLE (-6375 1475);
FORCEPROP 2 LAST CDS_LIB mstr_standard
J 0
(-6350 1575);
PAINT ORANGE (-6350 1575);
DISPLAY INVISIBLE (-6350 1575);
FORCEPROP 2 LAST PATH I116
J 0
(-6300 1650);
DISPLAY 1.021277 (-6300 1650);
PAINT ORANGE (-6300 1650);
DISPLAY INVISIBLE (-6300 1650);
FORCEPROP 1 LAST OFFPAGE TRUE
J 0
(-6025 1450);
DISPLAY 0.872340 (-6025 1450);
PAINT GREEN (-6025 1450);
DISPLAY INVISIBLE (-6025 1450);
FORCEADD OFFPAGE..1
(-6050 3375);
FORCEPROP 2 LAST $XR0 139 
J 0
(-6302 3375);
DISPLAY 0.638298 (-6302 3375);
PAINT MONO (-6302 3375);
FORCEPROP 1 LAST COMMENT_BODY TRUE
J 0
(-5925 3275);
DISPLAY 0.872340 (-5925 3275);
PAINT GREEN (-5925 3275);
DISPLAY INVISIBLE (-5925 3275);
FORCEPROP 2 LAST CDS_LIB mstr_standard
J 0
(-6050 3375);
PAINT ORANGE (-6050 3375);
DISPLAY INVISIBLE (-6050 3375);
FORCEPROP 2 LAST PATH I117
J 0
(-6000 3450);
DISPLAY 1.021277 (-6000 3450);
PAINT ORANGE (-6000 3450);
DISPLAY INVISIBLE (-6000 3450);
FORCEPROP 1 LAST OFFPAGE TRUE
J 0
(-5725 3250);
DISPLAY 0.872340 (-5725 3250);
PAINT GREEN (-5725 3250);
DISPLAY INVISIBLE (-5725 3250);
FORCEADD OFFPAGE..5
(-6050 3225);
FORCEPROP 2 LAST $XR0 139 
J 0
(-6305 3225);
DISPLAY 0.638298 (-6305 3225);
PAINT MONO (-6305 3225);
FORCEPROP 2 LAST CDS_LIB mstr_standard
J 0
(-6050 3225);
PAINT ORANGE (-6050 3225);
DISPLAY INVISIBLE (-6050 3225);
FORCEPROP 1 LAST COMMENT_BODY TRUE
J 0
(-5950 3150);
DISPLAY 0.872340 (-5950 3150);
PAINT GREEN (-5950 3150);
DISPLAY INVISIBLE (-5950 3150);
FORCEPROP 2 LAST PATH I118
J 0
(-6000 3300);
DISPLAY 1.021277 (-6000 3300);
PAINT ORANGE (-6000 3300);
DISPLAY INVISIBLE (-6000 3300);
FORCEPROP 1 LAST OFFPAGE TRUE
J 0
(-5725 3100);
DISPLAY 0.872340 (-5725 3100);
PAINT GREEN (-5725 3100);
DISPLAY INVISIBLE (-5725 3100);
FORCEADD OFFPAGE..1
(-6750 2375);
FORCEPROP 2 LAST $XR0 140 
J 0
(-7002 2375);
DISPLAY 0.638298 (-7002 2375);
PAINT MONO (-7002 2375);
FORCEPROP 2 LAST CDS_LIB mstr_standard
J 0
(-6750 2375);
PAINT ORANGE (-6750 2375);
DISPLAY INVISIBLE (-6750 2375);
FORCEPROP 2 LAST PATH I127
J 0
(-6700 2450);
DISPLAY 1.021277 (-6700 2450);
PAINT ORANGE (-6700 2450);
DISPLAY INVISIBLE (-6700 2450);
FORCEPROP 1 LAST OFFPAGE TRUE
J 0
(-6425 2250);
DISPLAY 0.872340 (-6425 2250);
PAINT GREEN (-6425 2250);
DISPLAY INVISIBLE (-6425 2250);
FORCEPROP 1 LAST COMMENT_BODY TRUE
J 0
(-6625 2275);
DISPLAY 0.872340 (-6625 2275);
PAINT GREEN (-6625 2275);
DISPLAY INVISIBLE (-6625 2275);
FORCEADD RES..1
(-2425 2375);
FORCEPROP 1 LAST VALUE 33.2
J 2
(-2450 2325);
DISPLAY 0.617021 (-2450 2325);
PAINT SKYBLUE (-2450 2325);
FORCEPROP 1 LAST PART_NUMBER G21796-074
J 0
(-2725 2375);
DISPLAY 0.617021 (-2725 2375);
PAINT BLUE (-2725 2375);
FORCEPROP 1 LASTPIN (-2525 2375) $PN 1
J 0
(-2513 2387);
DISPLAY 0.617021 (-2513 2387);
PAINT ORANGE (-2513 2387);
FORCEPROP 1 LASTPIN (-2325 2375) $PN 2
J 0
(-2363 2387);
DISPLAY 0.617021 (-2363 2387);
PAINT ORANGE (-2363 2387);
FORCEPROP 1 LAST TOLERANCE 1%
J 0
(-2350 2325);
DISPLAY 0.617021 (-2350 2325);
PAINT SKYBLUE (-2350 2325);
FORCEPROP 1 LAST LOCATION R9E9
J 0
(-2275 2375);
DISPLAY 0.617021 (-2275 2375);
PAINT AQUA (-2275 2375);
FORCEPROP 1 LAST WATTAGE 1/16W
J 2
(-2125 2325);
DISPLAY 0.617021 (-2125 2325);
PAINT SKYBLUE (-2125 2325);
FORCEPROP 1 LAST MATERIAL CHIP
J 0
(-2650 2350);
DISPLAY 0.617021 (-2650 2350);
PAINT SKYBLUE (-2650 2350);
DISPLAY INVISIBLE (-2650 2350);
FORCEPROP 2 LAST ROOM NIC_SPRV
J 0
(-2500 2475);
DISPLAY 1.021277 (-2500 2475);
PAINT ORANGE (-2500 2475);
DISPLAY INVISIBLE (-2500 2475);
FORCEPROP 2 LAST CDS_LIB mstr_discrete
J 0
(-2425 2375);
PAINT ORANGE (-2425 2375);
DISPLAY INVISIBLE (-2425 2375);
FORCEPROP 1 LAST PACK_TYPE 0402
J 0
(-2300 2400);
DISPLAY 0.617021 (-2300 2400);
PAINT SKYBLUE (-2300 2400);
DISPLAY INVISIBLE (-2300 2400);
FORCEPROP 2 LAST CDS_LOCATION R9E9
J 0
(-2275 2375);
DISPLAY 0.617021 (-2275 2375);
PAINT AQUA (-2275 2375);
DISPLAY INVISIBLE (-2275 2375);
FORCEPROP 1 LAST PATH I128
J 0
(-2475 2525);
DISPLAY 0.978723 (-2475 2525);
PAINT WHITE (-2475 2525);
DISPLAY INVISIBLE (-2475 2525);
FORCEPROP 2 LAST BOM_COST NT_GBE_BASE
J 0
(-2500 2525);
DISPLAY 1.021277 (-2500 2525);
PAINT ORANGE (-2500 2525);
DISPLAY INVISIBLE (-2500 2525);
FORCEPROP 2 LAST SEC 1
J 0
(-2475 2575);
PAINT MONO (-2475 2575);
DISPLAY INVISIBLE (-2475 2575);
FORCEPROP 2 LAST SEC_TYPE 0402
J 0
(-2475 2575);
DISPLAY 1.021277 (-2475 2575);
PAINT ORANGE (-2475 2575);
DISPLAY INVISIBLE (-2475 2575);
FORCEADD RES..1
(-1550 2325);
FORCEPROP 1 LAST PART_NUMBER G21796-074
J 0
(-1875 2325);
DISPLAY 0.617021 (-1875 2325);
PAINT BLUE (-1875 2325);
FORCEPROP 1 LAST VALUE 33.2
J 2
(-1575 2275);
DISPLAY 0.617021 (-1575 2275);
PAINT SKYBLUE (-1575 2275);
FORCEPROP 1 LASTPIN (-1650 2325) $PN 1
J 0
(-1638 2337);
DISPLAY 0.617021 (-1638 2337);
PAINT ORANGE (-1638 2337);
FORCEPROP 1 LAST LOCATION R9E5
J 0
(-1450 2325);
DISPLAY 0.617021 (-1450 2325);
PAINT AQUA (-1450 2325);
FORCEPROP 1 LAST TOLERANCE 1%
J 0
(-1475 2275);
DISPLAY 0.617021 (-1475 2275);
PAINT SKYBLUE (-1475 2275);
FORCEPROP 1 LASTPIN (-1450 2325) $PN 2
J 0
(-1488 2337);
DISPLAY 0.617021 (-1488 2337);
PAINT ORANGE (-1488 2337);
FORCEPROP 1 LAST WATTAGE 1/16W
J 2
(-1275 2275);
DISPLAY 0.617021 (-1275 2275);
PAINT SKYBLUE (-1275 2275);
FORCEPROP 2 LAST ROOM NIC_SPRV
J 0
(-1800 2475);
DISPLAY 1.021277 (-1800 2475);
PAINT ORANGE (-1800 2475);
DISPLAY INVISIBLE (-1800 2475);
FORCEPROP 1 LAST MATERIAL CHIP
J 0
(-1775 2300);
DISPLAY 0.617021 (-1775 2300);
PAINT SKYBLUE (-1775 2300);
DISPLAY INVISIBLE (-1775 2300);
FORCEPROP 1 LAST PATH I129
J 0
(-1600 2475);
DISPLAY 0.978723 (-1600 2475);
PAINT WHITE (-1600 2475);
DISPLAY INVISIBLE (-1600 2475);
FORCEPROP 2 LAST CDS_LIB mstr_discrete
J 0
(-1550 2325);
PAINT ORANGE (-1550 2325);
DISPLAY INVISIBLE (-1550 2325);
FORCEPROP 2 LAST SEC 1
J 0
(-1600 2525);
PAINT MONO (-1600 2525);
DISPLAY INVISIBLE (-1600 2525);
FORCEPROP 2 LAST SEC_TYPE 0402
J 0
(-1600 2525);
DISPLAY 1.021277 (-1600 2525);
PAINT ORANGE (-1600 2525);
DISPLAY INVISIBLE (-1600 2525);
FORCEPROP 2 LAST BOM_COST NT_GBE_BASE
J 0
(-1800 2525);
DISPLAY 1.021277 (-1800 2525);
PAINT ORANGE (-1800 2525);
DISPLAY INVISIBLE (-1800 2525);
FORCEPROP 1 LAST PACK_TYPE 0402
J 0
(-1450 2325);
DISPLAY 0.617021 (-1450 2325);
PAINT SKYBLUE (-1450 2325);
DISPLAY INVISIBLE (-1450 2325);
FORCEPROP 2 LAST CDS_LOCATION R9E5
J 0
(-1450 2325);
DISPLAY 0.617021 (-1450 2325);
PAINT AQUA (-1450 2325);
DISPLAY INVISIBLE (-1450 2325);
FORCEADD RES..1
(-2400 2275);
FORCEPROP 1 LAST VALUE 33.2
J 2
(-2450 2225);
DISPLAY 0.617021 (-2450 2225);
PAINT SKYBLUE (-2450 2225);
FORCEPROP 1 LAST PART_NUMBER G21796-074
J 0
(-2725 2275);
DISPLAY 0.617021 (-2725 2275);
PAINT BLUE (-2725 2275);
FORCEPROP 1 LASTPIN (-2500 2275) $PN 1
J 0
(-2488 2287);
DISPLAY 0.617021 (-2488 2287);
PAINT ORANGE (-2488 2287);
FORCEPROP 1 LASTPIN (-2300 2275) $PN 2
J 0
(-2338 2287);
DISPLAY 0.617021 (-2338 2287);
PAINT ORANGE (-2338 2287);
FORCEPROP 1 LAST TOLERANCE 1%
J 0
(-2350 2225);
DISPLAY 0.617021 (-2350 2225);
PAINT SKYBLUE (-2350 2225);
FORCEPROP 1 LAST WATTAGE 1/16W
J 2
(-2125 2225);
DISPLAY 0.617021 (-2125 2225);
PAINT SKYBLUE (-2125 2225);
FORCEPROP 1 LAST LOCATION R9E8
J 0
(-2275 2275);
DISPLAY 0.617021 (-2275 2275);
PAINT AQUA (-2275 2275);
FORCEPROP 1 LAST MATERIAL CHIP
J 0
(-2625 2250);
DISPLAY 0.617021 (-2625 2250);
PAINT SKYBLUE (-2625 2250);
DISPLAY INVISIBLE (-2625 2250);
FORCEPROP 2 LAST CDS_LIB mstr_discrete
J 0
(-2400 2275);
PAINT ORANGE (-2400 2275);
DISPLAY INVISIBLE (-2400 2275);
FORCEPROP 1 LAST PACK_TYPE 0402
J 0
(-2325 2300);
DISPLAY 0.617021 (-2325 2300);
PAINT SKYBLUE (-2325 2300);
DISPLAY INVISIBLE (-2325 2300);
FORCEPROP 1 LAST PATH I130
J 0
(-2450 2425);
DISPLAY 0.978723 (-2450 2425);
PAINT WHITE (-2450 2425);
DISPLAY INVISIBLE (-2450 2425);
FORCEPROP 2 LAST SEC 1
J 0
(-2450 2475);
PAINT MONO (-2450 2475);
DISPLAY INVISIBLE (-2450 2475);
FORCEPROP 2 LAST SEC_TYPE 0402
J 0
(-2450 2475);
DISPLAY 1.021277 (-2450 2475);
PAINT ORANGE (-2450 2475);
DISPLAY INVISIBLE (-2450 2475);
FORCEPROP 2 LAST ROOM NIC_SPRV
J 0
(-2425 2350);
DISPLAY 1.021277 (-2425 2350);
PAINT ORANGE (-2425 2350);
DISPLAY INVISIBLE (-2425 2350);
FORCEPROP 2 LAST BOM_COST NT_GBE_BASE
J 0
(-2425 2400);
DISPLAY 1.021277 (-2425 2400);
PAINT ORANGE (-2425 2400);
DISPLAY INVISIBLE (-2425 2400);
FORCEPROP 2 LAST CDS_LOCATION R9E8
J 0
(-2275 2275);
DISPLAY 0.617021 (-2275 2275);
PAINT AQUA (-2275 2275);
DISPLAY INVISIBLE (-2275 2275);
FORCEADD OFFPAGE..2
(-875 2375);
FORCEPROP 2 LAST $XR0 140 
J 0
(-686 2375);
DISPLAY 0.638298 (-686 2375);
PAINT MONO (-686 2375);
FORCEPROP 1 LAST COMMENT_BODY TRUE
J 0
(-920 2280);
DISPLAY 0.872340 (-920 2280);
PAINT GREEN (-920 2280);
DISPLAY INVISIBLE (-920 2280);
FORCEPROP 2 LAST CDS_LIB mstr_standard
J 0
(-875 2375);
PAINT ORANGE (-875 2375);
DISPLAY INVISIBLE (-875 2375);
FORCEPROP 2 LAST PATH I131
J 0
(-825 2450);
DISPLAY 1.021277 (-825 2450);
PAINT ORANGE (-825 2450);
DISPLAY INVISIBLE (-825 2450);
FORCEPROP 1 LAST OFFPAGE TRUE
J 0
(-550 2250);
DISPLAY 0.872340 (-550 2250);
PAINT GREEN (-550 2250);
DISPLAY INVISIBLE (-550 2250);
FORCEADD OFFPAGE..2
(-875 2325);
FORCEPROP 2 LAST $XR0 140 
J 0
(-686 2325);
DISPLAY 0.638298 (-686 2325);
PAINT MONO (-686 2325);
FORCEPROP 1 LAST COMMENT_BODY TRUE
J 0
(-920 2230);
DISPLAY 0.872340 (-920 2230);
PAINT GREEN (-920 2230);
DISPLAY INVISIBLE (-920 2230);
FORCEPROP 2 LAST CDS_LIB mstr_standard
J 0
(-875 2325);
PAINT ORANGE (-875 2325);
DISPLAY INVISIBLE (-875 2325);
FORCEPROP 2 LAST PATH I132
J 0
(-825 2400);
DISPLAY 1.021277 (-825 2400);
PAINT ORANGE (-825 2400);
DISPLAY INVISIBLE (-825 2400);
FORCEPROP 1 LAST OFFPAGE TRUE
J 0
(-550 2200);
DISPLAY 0.872340 (-550 2200);
PAINT GREEN (-550 2200);
DISPLAY INVISIBLE (-550 2200);
FORCEADD OFFPAGE..2
(-875 2275);
FORCEPROP 2 LAST $XR0 140 
J 0
(-686 2275);
DISPLAY 0.638298 (-686 2275);
PAINT MONO (-686 2275);
FORCEPROP 1 LAST COMMENT_BODY TRUE
J 0
(-920 2180);
DISPLAY 0.872340 (-920 2180);
PAINT GREEN (-920 2180);
DISPLAY INVISIBLE (-920 2180);
FORCEPROP 2 LAST CDS_LIB mstr_standard
J 0
(-875 2275);
PAINT ORANGE (-875 2275);
DISPLAY INVISIBLE (-875 2275);
FORCEPROP 1 LAST OFFPAGE TRUE
J 0
(-550 2150);
DISPLAY 0.872340 (-550 2150);
PAINT GREEN (-550 2150);
DISPLAY INVISIBLE (-550 2150);
FORCEPROP 2 LAST PATH I133
J 0
(-700 2350);
DISPLAY 1.021277 (-700 2350);
PAINT ORANGE (-700 2350);
DISPLAY INVISIBLE (-700 2350);
FORCEADD CAP..1
(-5975 4275);
FORCEPROP 1 LAST PACK_TYPE 0603
J 0
(-5925 4075);
DISPLAY 0.617021 (-5925 4075);
PAINT SKYBLUE (-5925 4075);
FORCEPROP 1 LASTPIN (-5975 4175) $PN 2
J 0
(-5965 4155);
DISPLAY 0.617021 (-5965 4155);
PAINT ORANGE (-5965 4155);
FORCEPROP 1 LASTPIN (-5975 4375) $PN 1
J 0
(-5965 4355);
DISPLAY 0.617021 (-5965 4355);
PAINT ORANGE (-5965 4355);
FORCEPROP 1 LAST MATERIAL X6S
J 0
(-5925 4175);
DISPLAY 0.617021 (-5925 4175);
PAINT SKYBLUE (-5925 4175);
FORCEPROP 1 LAST VOLTAGE 6.3V
J 0
(-5925 4275);
DISPLAY 0.617021 (-5925 4275);
PAINT SKYBLUE (-5925 4275);
FORCEPROP 1 LAST TOLERANCE 20%
J 0
(-5925 4225);
DISPLAY 0.617021 (-5925 4225);
PAINT SKYBLUE (-5925 4225);
FORCEPROP 1 LAST VALUE 10UF
J 0
(-5925 4325);
DISPLAY 0.617021 (-5925 4325);
PAINT SKYBLUE (-5925 4325);
FORCEPROP 1 LAST PART_NUMBER E15431-002
J 0
(-5925 4125);
DISPLAY 0.617021 (-5925 4125);
PAINT BLUE (-5925 4125);
FORCEPROP 1 LAST LOCATION C1T4
J 0
(-5925 4375);
DISPLAY 0.617021 (-5925 4375);
PAINT AQUA (-5925 4375);
FORCEPROP 2 LAST CDS_LIB mstr_discrete
J 0
(-5975 4275);
PAINT ORANGE (-5975 4275);
DISPLAY INVISIBLE (-5975 4275);
FORCEPROP 1 LAST PATH I134
J 0
(-5925 4425);
DISPLAY 0.978723 (-5925 4425);
PAINT WHITE (-5925 4425);
DISPLAY INVISIBLE (-5925 4425);
FORCEPROP 2 LAST BOM_COST NT_GBE_BASE
J 0
(-5925 4475);
DISPLAY 1.021277 (-5925 4475);
PAINT ORANGE (-5925 4475);
DISPLAY INVISIBLE (-5925 4475);
FORCEPROP 2 LAST ROOM NIC_SPRV
J 0
(-5925 4425);
DISPLAY 1.021277 (-5925 4425);
PAINT ORANGE (-5925 4425);
DISPLAY INVISIBLE (-5925 4425);
FORCEPROP 2 LAST SEC_TYPE 0603
J 0
(-5925 4475);
DISPLAY 1.021277 (-5925 4475);
PAINT ORANGE (-5925 4475);
DISPLAY INVISIBLE (-5925 4475);
FORCEPROP 2 LAST SEC 1
J 0
(-5925 4475);
PAINT MONO (-5925 4475);
DISPLAY INVISIBLE (-5925 4475);
FORCEPROP 2 LAST CDS_LOCATION C1T4
J 0
(-5925 4375);
DISPLAY 0.617021 (-5925 4375);
PAINT AQUA (-5925 4375);
DISPLAY INVISIBLE (-5925 4375);
FORCEADD CAP..1
(-6325 3975);
FORCEPROP 1 LASTPIN (-6325 3875) $PN 2
J 0
(-6315 3855);
DISPLAY 0.617021 (-6315 3855);
PAINT ORANGE (-6315 3855);
FORCEPROP 1 LASTPIN (-6325 4075) $PN 1
J 0
(-6315 4055);
DISPLAY 0.617021 (-6315 4055);
PAINT ORANGE (-6315 4055);
FORCEPROP 1 LAST VALUE 10UF
J 0
(-6275 4025);
DISPLAY 0.617021 (-6275 4025);
PAINT SKYBLUE (-6275 4025);
FORCEPROP 1 LAST TOLERANCE 20%
J 0
(-6275 3925);
DISPLAY 0.617021 (-6275 3925);
PAINT SKYBLUE (-6275 3925);
FORCEPROP 1 LAST VOLTAGE 6.3V
J 0
(-6275 3975);
DISPLAY 0.617021 (-6275 3975);
PAINT SKYBLUE (-6275 3975);
FORCEPROP 1 LAST MATERIAL X6S
J 0
(-6275 3875);
DISPLAY 0.617021 (-6275 3875);
PAINT SKYBLUE (-6275 3875);
FORCEPROP 1 LAST PART_NUMBER E15431-002
J 0
(-6275 3825);
DISPLAY 0.617021 (-6275 3825);
PAINT BLUE (-6275 3825);
FORCEPROP 1 LAST LOCATION C1R30
J 0
(-6275 4075);
DISPLAY 0.617021 (-6275 4075);
PAINT AQUA (-6275 4075);
FORCEPROP 1 LAST PACK_TYPE 0603
J 0
(-6275 3775);
DISPLAY 0.617021 (-6275 3775);
PAINT SKYBLUE (-6275 3775);
FORCEPROP 2 LAST CDS_LIB mstr_discrete
J 0
(-6325 3975);
PAINT ORANGE (-6325 3975);
DISPLAY INVISIBLE (-6325 3975);
FORCEPROP 2 LAST CDS_LOCATION C1R30
J 0
(-6275 4075);
DISPLAY 0.617021 (-6275 4075);
PAINT AQUA (-6275 4075);
DISPLAY INVISIBLE (-6275 4075);
FORCEPROP 2 LAST SEC_TYPE 0603
J 0
(-6275 4175);
DISPLAY 1.021277 (-6275 4175);
PAINT ORANGE (-6275 4175);
DISPLAY INVISIBLE (-6275 4175);
FORCEPROP 2 LAST BOM_COST NT_GBE_BASE
J 0
(-6275 4175);
DISPLAY 1.021277 (-6275 4175);
PAINT ORANGE (-6275 4175);
DISPLAY INVISIBLE (-6275 4175);
FORCEPROP 2 LAST SEC 1
J 0
(-6275 4175);
PAINT MONO (-6275 4175);
DISPLAY INVISIBLE (-6275 4175);
FORCEPROP 1 LAST PATH I135
J 0
(-6275 4125);
DISPLAY 0.978723 (-6275 4125);
PAINT WHITE (-6275 4125);
DISPLAY INVISIBLE (-6275 4125);
FORCEPROP 2 LAST ROOM NIC_SPRV
J 0
(-6275 4125);
DISPLAY 1.021277 (-6275 4125);
PAINT ORANGE (-6275 4125);
DISPLAY INVISIBLE (-6275 4125);
FORCEADD CAP..1
(-6725 3750);
FORCEPROP 1 LASTPIN (-6725 3650) $PN 2
J 0
(-6715 3630);
DISPLAY 0.617021 (-6715 3630);
PAINT ORANGE (-6715 3630);
FORCEPROP 1 LASTPIN (-6725 3850) $PN 1
J 0
(-6715 3830);
DISPLAY 0.617021 (-6715 3830);
PAINT ORANGE (-6715 3830);
FORCEPROP 1 LAST MATERIAL X6S
J 0
(-6675 3650);
DISPLAY 0.617021 (-6675 3650);
PAINT SKYBLUE (-6675 3650);
FORCEPROP 1 LAST PACK_TYPE 0603
J 0
(-6675 3550);
DISPLAY 0.617021 (-6675 3550);
PAINT SKYBLUE (-6675 3550);
FORCEPROP 1 LAST VALUE 10UF
J 0
(-6675 3800);
DISPLAY 0.617021 (-6675 3800);
PAINT SKYBLUE (-6675 3800);
FORCEPROP 1 LAST PART_NUMBER E15431-002
J 0
(-6675 3600);
DISPLAY 0.617021 (-6675 3600);
PAINT BLUE (-6675 3600);
FORCEPROP 1 LAST LOCATION C1R22
J 0
(-6675 3850);
DISPLAY 0.617021 (-6675 3850);
PAINT AQUA (-6675 3850);
FORCEPROP 1 LAST VOLTAGE 6.3V
J 0
(-6675 3750);
DISPLAY 0.617021 (-6675 3750);
PAINT SKYBLUE (-6675 3750);
FORCEPROP 1 LAST TOLERANCE 20%
J 0
(-6675 3700);
DISPLAY 0.617021 (-6675 3700);
PAINT SKYBLUE (-6675 3700);
FORCEPROP 2 LAST CDS_LIB mstr_discrete
J 0
(-6725 3750);
PAINT ORANGE (-6725 3750);
DISPLAY INVISIBLE (-6725 3750);
FORCEPROP 2 LAST CDS_LOCATION C1R22
J 0
(-6675 3850);
DISPLAY 0.617021 (-6675 3850);
PAINT AQUA (-6675 3850);
DISPLAY INVISIBLE (-6675 3850);
FORCEPROP 1 LAST PATH I136
J 0
(-6675 3900);
DISPLAY 0.978723 (-6675 3900);
PAINT WHITE (-6675 3900);
DISPLAY INVISIBLE (-6675 3900);
FORCEPROP 2 LAST ROOM NIC_SPRV
J 0
(-6675 3900);
DISPLAY 1.021277 (-6675 3900);
PAINT ORANGE (-6675 3900);
DISPLAY INVISIBLE (-6675 3900);
FORCEPROP 2 LAST SEC 1
J 0
(-6675 3950);
PAINT MONO (-6675 3950);
DISPLAY INVISIBLE (-6675 3950);
FORCEPROP 2 LAST BOM_COST NT_GBE_BASE
J 0
(-6675 3950);
DISPLAY 1.021277 (-6675 3950);
PAINT ORANGE (-6675 3950);
DISPLAY INVISIBLE (-6675 3950);
FORCEPROP 2 LAST SEC_TYPE 0603
J 0
(-6675 3950);
DISPLAY 1.021277 (-6675 3950);
PAINT ORANGE (-6675 3950);
DISPLAY INVISIBLE (-6675 3950);
FORCEADD GND..1
(-6725 3500);
FORCEPROP 3 LASTPIN (-6725 3550) SIG_NAME GND\g
J 0
(-6715 3560);
DISPLAY 0.659574 (-6715 3560);
PAINT MONO (-6715 3560);
DISPLAY INVISIBLE (-6715 3560);
FORCEPROP 1 LAST BODY_TYPE PLUMBING
J 0
(-6770 3457);
DISPLAY 0.340426 (-6770 3457);
PAINT GREEN (-6770 3457);
DISPLAY INVISIBLE (-6770 3457);
FORCEPROP 2 LAST CDS_LIB mstr_symbols
J 0
(-6725 3500);
PAINT ORANGE (-6725 3500);
DISPLAY INVISIBLE (-6725 3500);
FORCEPROP 1 LAST VOLTAGE 0.0V
J 0
(-6770 3457);
DISPLAY 0.340426 (-6770 3457);
PAINT SKYBLUE (-6770 3457);
DISPLAY INVISIBLE (-6770 3457);
FORCEPROP 1 LAST HDL_POWER GND
J 0
(-6725 3650);
DISPLAY 0.872340 (-6725 3650);
PAINT GREEN (-6725 3650);
DISPLAY INVISIBLE (-6725 3650);
FORCEPROP 1 LAST PATH I137
J 0
(-6650 3500);
DISPLAY 0.872340 (-6650 3500);
PAINT AQUA (-6650 3500);
DISPLAY INVISIBLE (-6650 3500);
FORCEPROP 1 LAST SIZE 1B
J 0
(-6650 3450);
DISPLAY 0.872340 (-6650 3450);
PAINT AQUA (-6650 3450);
DISPLAY INVISIBLE (-6650 3450);
FORCEADD GND..1
(-6325 3750);
FORCEPROP 3 LASTPIN (-6325 3800) SIG_NAME GND\g
J 0
(-6315 3810);
DISPLAY 0.659574 (-6315 3810);
PAINT MONO (-6315 3810);
DISPLAY INVISIBLE (-6315 3810);
FORCEPROP 1 LAST PATH I138
J 0
(-6250 3750);
DISPLAY 0.872340 (-6250 3750);
PAINT AQUA (-6250 3750);
DISPLAY INVISIBLE (-6250 3750);
FORCEPROP 1 LAST BODY_TYPE PLUMBING
J 0
(-6370 3707);
DISPLAY 0.340426 (-6370 3707);
PAINT GREEN (-6370 3707);
DISPLAY INVISIBLE (-6370 3707);
FORCEPROP 1 LAST SIZE 1B
J 0
(-6250 3700);
DISPLAY 0.872340 (-6250 3700);
PAINT AQUA (-6250 3700);
DISPLAY INVISIBLE (-6250 3700);
FORCEPROP 2 LAST CDS_LIB mstr_symbols
J 0
(-6325 3750);
PAINT ORANGE (-6325 3750);
DISPLAY INVISIBLE (-6325 3750);
FORCEPROP 1 LAST VOLTAGE 0.0V
J 0
(-6370 3707);
DISPLAY 0.340426 (-6370 3707);
PAINT SKYBLUE (-6370 3707);
DISPLAY INVISIBLE (-6370 3707);
FORCEPROP 1 LAST HDL_POWER GND
J 0
(-6325 3900);
DISPLAY 0.872340 (-6325 3900);
PAINT GREEN (-6325 3900);
DISPLAY INVISIBLE (-6325 3900);
FORCEADD GND..1
(-5975 4050);
FORCEPROP 3 LASTPIN (-5975 4100) SIG_NAME GND\g
J 0
(-5965 4110);
DISPLAY 0.659574 (-5965 4110);
PAINT MONO (-5965 4110);
DISPLAY INVISIBLE (-5965 4110);
FORCEPROP 1 LAST VOLTAGE 0.0V
J 0
(-6020 4007);
DISPLAY 0.340426 (-6020 4007);
PAINT SKYBLUE (-6020 4007);
DISPLAY INVISIBLE (-6020 4007);
FORCEPROP 1 LAST BODY_TYPE PLUMBING
J 0
(-6020 4007);
DISPLAY 0.340426 (-6020 4007);
PAINT GREEN (-6020 4007);
DISPLAY INVISIBLE (-6020 4007);
FORCEPROP 1 LAST PATH I139
J 0
(-5900 4050);
DISPLAY 0.872340 (-5900 4050);
PAINT AQUA (-5900 4050);
DISPLAY INVISIBLE (-5900 4050);
FORCEPROP 2 LAST CDS_LIB mstr_symbols
J 0
(-5975 4050);
PAINT ORANGE (-5975 4050);
DISPLAY INVISIBLE (-5975 4050);
FORCEPROP 1 LAST SIZE 1B
J 0
(-5900 4000);
DISPLAY 0.872340 (-5900 4000);
PAINT AQUA (-5900 4000);
DISPLAY INVISIBLE (-5900 4000);
FORCEPROP 1 LAST HDL_POWER GND
J 0
(-5975 4200);
DISPLAY 0.872340 (-5975 4200);
PAINT GREEN (-5975 4200);
DISPLAY INVISIBLE (-5975 4200);
FORCEADD CAP..1
(-5275 875);
FORCEPROP 1 LASTPIN (-5275 775) $PN 2
J 0
(-5265 755);
DISPLAY 0.617021 (-5265 755);
PAINT ORANGE (-5265 755);
FORCEPROP 1 LASTPIN (-5275 975) $PN 1
J 0
(-5265 955);
DISPLAY 0.617021 (-5265 955);
PAINT ORANGE (-5265 955);
FORCEPROP 1 LAST TOLERANCE 20%
J 0
(-5225 825);
DISPLAY 0.617021 (-5225 825);
PAINT SKYBLUE (-5225 825);
FORCEPROP 1 LAST VOLTAGE 16V
J 0
(-5225 875);
DISPLAY 0.617021 (-5225 875);
PAINT SKYBLUE (-5225 875);
FORCEPROP 1 LAST PACK_TYPE 1210
J 0
(-5225 675);
DISPLAY 0.617021 (-5225 675);
PAINT SKYBLUE (-5225 675);
FORCEPROP 1 LAST VALUE 47UF
J 0
(-5225 925);
DISPLAY 0.617021 (-5225 925);
PAINT SKYBLUE (-5225 925);
FORCEPROP 1 LAST PART_NUMBER D38464-007
J 0
(-5225 725);
DISPLAY 0.617021 (-5225 725);
PAINT BLUE (-5225 725);
FORCEPROP 1 LAST LOCATION C9F2
J 0
(-5225 975);
DISPLAY 0.617021 (-5225 975);
PAINT AQUA (-5225 975);
FORCEPROP 1 LAST MATERIAL EMPTY
J 0
(-5225 775);
DISPLAY 0.617021 (-5225 775);
PAINT RED (-5225 775);
FORCEPROP 2 LAST CDS_LIB mstr_discrete
J 0
(-5275 875);
PAINT ORANGE (-5275 875);
DISPLAY INVISIBLE (-5275 875);
FORCEPROP 2 LAST CDS_LOCATION C9F2
J 0
(-5225 975);
DISPLAY 0.617021 (-5225 975);
PAINT AQUA (-5225 975);
DISPLAY INVISIBLE (-5225 975);
FORCEPROP 2 LAST BOM_COST NT_GBE_BASE
J 0
(-5225 1075);
DISPLAY 1.021277 (-5225 1075);
PAINT ORANGE (-5225 1075);
DISPLAY INVISIBLE (-5225 1075);
FORCEPROP 2 LAST CDS_SEC 1
J 0
(-5225 1075);
PAINT MONO (-5225 1075);
DISPLAY INVISIBLE (-5225 1075);
FORCEPROP 2 LAST ROOM NIC_SPRV
J 0
(-5225 1025);
DISPLAY 1.021277 (-5225 1025);
PAINT ORANGE (-5225 1025);
DISPLAY INVISIBLE (-5225 1025);
FORCEPROP 1 LAST PATH I140
J 0
(-5225 1025);
DISPLAY 0.978723 (-5225 1025);
PAINT WHITE (-5225 1025);
DISPLAY INVISIBLE (-5225 1025);
FORCEPROP 2 LAST $SEC 1
J 0
(-5225 1075);
PAINT MONO (-5225 1075);
DISPLAY INVISIBLE (-5225 1075);
FORCEADD CAP..1
(-5025 875);
FORCEPROP 1 LASTPIN (-5025 775) $PN 2
J 0
(-5015 755);
DISPLAY 0.617021 (-5015 755);
PAINT ORANGE (-5015 755);
FORCEPROP 1 LAST TOLERANCE 20%
J 0
(-4975 825);
DISPLAY 0.617021 (-4975 825);
PAINT SKYBLUE (-4975 825);
FORCEPROP 1 LAST MATERIAL X6S
J 0
(-4975 775);
DISPLAY 0.617021 (-4975 775);
PAINT SKYBLUE (-4975 775);
FORCEPROP 1 LASTPIN (-5025 975) $PN 1
J 0
(-5015 955);
DISPLAY 0.617021 (-5015 955);
PAINT ORANGE (-5015 955);
FORCEPROP 1 LAST VOLTAGE 6.3V
J 0
(-4975 875);
DISPLAY 0.617021 (-4975 875);
PAINT SKYBLUE (-4975 875);
FORCEPROP 1 LAST PACK_TYPE 0603
J 0
(-4975 675);
DISPLAY 0.617021 (-4975 675);
PAINT SKYBLUE (-4975 675);
FORCEPROP 1 LAST VALUE 10UF
J 0
(-4975 925);
DISPLAY 0.617021 (-4975 925);
PAINT SKYBLUE (-4975 925);
FORCEPROP 1 LAST PART_NUMBER E15431-002
J 0
(-4975 725);
DISPLAY 0.617021 (-4975 725);
PAINT BLUE (-4975 725);
FORCEPROP 1 LAST LOCATION C1R13
J 0
(-4975 975);
DISPLAY 0.617021 (-4975 975);
PAINT AQUA (-4975 975);
FORCEPROP 2 LAST CDS_LIB mstr_discrete
J 0
(-5025 875);
PAINT ORANGE (-5025 875);
DISPLAY INVISIBLE (-5025 875);
FORCEPROP 2 LAST CDS_LOCATION C1R13
J 0
(-4975 975);
DISPLAY 0.617021 (-4975 975);
PAINT AQUA (-4975 975);
DISPLAY INVISIBLE (-4975 975);
FORCEPROP 2 LAST BOM_COST NT_GBE_BASE
J 0
(-4975 1075);
DISPLAY 1.021277 (-4975 1075);
PAINT ORANGE (-4975 1075);
DISPLAY INVISIBLE (-4975 1075);
FORCEPROP 2 LAST CDS_SEC 1
J 0
(-4975 1075);
PAINT MONO (-4975 1075);
DISPLAY INVISIBLE (-4975 1075);
FORCEPROP 2 LAST ROOM NIC_SPRV
J 0
(-4975 1025);
DISPLAY 1.021277 (-4975 1025);
PAINT ORANGE (-4975 1025);
DISPLAY INVISIBLE (-4975 1025);
FORCEPROP 1 LAST PATH I142
J 0
(-4975 1025);
DISPLAY 0.978723 (-4975 1025);
PAINT WHITE (-4975 1025);
DISPLAY INVISIBLE (-4975 1025);
FORCEPROP 2 LAST $SEC 1
J 0
(-4975 1075);
PAINT MONO (-4975 1075);
DISPLAY INVISIBLE (-4975 1075);
FORCEADD CAP_A..1
(-4775 875);
FORCEPROP 1 LASTPIN (-4775 775) $PN 2
J 0
(-4765 755);
DISPLAY 0.617021 (-4765 755);
PAINT ORANGE (-4765 755);
FORCEPROP 1 LAST TOLERANCE 10%
J 0
(-4725 825);
DISPLAY 0.617021 (-4725 825);
PAINT SKYBLUE (-4725 825);
FORCEPROP 1 LAST VOLTAGE 16V
J 0
(-4725 875);
DISPLAY 0.617021 (-4725 875);
PAINT SKYBLUE (-4725 875);
FORCEPROP 1 LAST MATERIAL X7R
J 0
(-4725 775);
DISPLAY 0.617021 (-4725 775);
PAINT SKYBLUE (-4725 775);
FORCEPROP 1 LASTPIN (-4775 975) $PN 1
J 0
(-4765 955);
DISPLAY 0.617021 (-4765 955);
PAINT ORANGE (-4765 955);
FORCEPROP 1 LAST PACK_TYPE 0402V
J 0
(-4725 675);
DISPLAY 0.617021 (-4725 675);
PAINT SKYBLUE (-4725 675);
FORCEPROP 1 LAST VALUE 0.1UF
J 0
(-4725 925);
DISPLAY 0.617021 (-4725 925);
PAINT SKYBLUE (-4725 925);
FORCEPROP 1 LAST PART_NUMBER A36096-030
J 0
(-4725 725);
DISPLAY 0.617021 (-4725 725);
PAINT BLUE (-4725 725);
FORCEPROP 1 LAST LOCATION C1R20
J 0
(-4725 975);
DISPLAY 0.617021 (-4725 975);
PAINT AQUA (-4725 975);
FORCEPROP 2 LAST CDS_LOCATION C1R20
J 0
(-4725 975);
DISPLAY 0.617021 (-4725 975);
PAINT AQUA (-4725 975);
DISPLAY INVISIBLE (-4725 975);
FORCEPROP 2 LAST CDS_LIB dev_discrete
J 0
(-4775 875);
PAINT ORANGE (-4775 875);
DISPLAY INVISIBLE (-4775 875);
FORCEPROP 2 LAST $SEC 1
J 0
(-4725 1075);
PAINT MONO (-4725 1075);
DISPLAY INVISIBLE (-4725 1075);
FORCEPROP 2 LAST CDS_SEC 1
J 0
(-4725 1075);
PAINT MONO (-4725 1075);
DISPLAY INVISIBLE (-4725 1075);
FORCEPROP 2 LAST BOM_COST NT_GBE_BASE
J 0
(-4725 1075);
DISPLAY 1.021277 (-4725 1075);
PAINT ORANGE (-4725 1075);
DISPLAY INVISIBLE (-4725 1075);
FORCEPROP 2 LAST ROOM NIC_SPRV
J 0
(-4725 1025);
DISPLAY 1.021277 (-4725 1025);
PAINT ORANGE (-4725 1025);
DISPLAY INVISIBLE (-4725 1025);
FORCEPROP 1 LAST PATH I143
J 0
(-4725 1025);
DISPLAY 0.978723 (-4725 1025);
PAINT WHITE (-4725 1025);
DISPLAY INVISIBLE (-4725 1025);
FORCEADD CAP_A..1
(-4525 875);
FORCEPROP 1 LASTPIN (-4525 775) $PN 2
J 0
(-4515 755);
DISPLAY 0.617021 (-4515 755);
PAINT ORANGE (-4515 755);
FORCEPROP 1 LAST LOCATION C1T3
J 0
(-4475 975);
DISPLAY 0.617021 (-4475 975);
PAINT AQUA (-4475 975);
FORCEPROP 1 LAST TOLERANCE 10%
J 0
(-4475 825);
DISPLAY 0.617021 (-4475 825);
PAINT SKYBLUE (-4475 825);
FORCEPROP 1 LAST VOLTAGE 16V
J 0
(-4475 875);
DISPLAY 0.617021 (-4475 875);
PAINT SKYBLUE (-4475 875);
FORCEPROP 1 LAST MATERIAL X7R
J 0
(-4475 775);
DISPLAY 0.617021 (-4475 775);
PAINT SKYBLUE (-4475 775);
FORCEPROP 1 LASTPIN (-4525 975) $PN 1
J 0
(-4515 955);
DISPLAY 0.617021 (-4515 955);
PAINT ORANGE (-4515 955);
FORCEPROP 1 LAST PACK_TYPE 0402V
J 0
(-4475 675);
DISPLAY 0.617021 (-4475 675);
PAINT SKYBLUE (-4475 675);
FORCEPROP 1 LAST VALUE 0.1UF
J 0
(-4475 925);
DISPLAY 0.617021 (-4475 925);
PAINT SKYBLUE (-4475 925);
FORCEPROP 1 LAST PART_NUMBER A36096-030
J 0
(-4475 725);
DISPLAY 0.617021 (-4475 725);
PAINT BLUE (-4475 725);
FORCEPROP 2 LAST CDS_LOCATION C1T3
J 0
(-4475 975);
DISPLAY 0.617021 (-4475 975);
PAINT AQUA (-4475 975);
DISPLAY INVISIBLE (-4475 975);
FORCEPROP 2 LAST CDS_LIB dev_discrete
J 0
(-4525 875);
PAINT ORANGE (-4525 875);
DISPLAY INVISIBLE (-4525 875);
FORCEPROP 1 LAST PATH I144
J 0
(-4475 1025);
DISPLAY 0.978723 (-4475 1025);
PAINT WHITE (-4475 1025);
DISPLAY INVISIBLE (-4475 1025);
FORCEPROP 2 LAST ROOM NIC_SPRV
J 0
(-4475 1025);
DISPLAY 1.021277 (-4475 1025);
PAINT ORANGE (-4475 1025);
DISPLAY INVISIBLE (-4475 1025);
FORCEPROP 2 LAST BOM_COST NT_GBE_BASE
J 0
(-4475 1075);
DISPLAY 1.021277 (-4475 1075);
PAINT ORANGE (-4475 1075);
DISPLAY INVISIBLE (-4475 1075);
FORCEPROP 2 LAST $SEC 1
J 0
(-4475 1075);
PAINT MONO (-4475 1075);
DISPLAY INVISIBLE (-4475 1075);
FORCEPROP 2 LAST CDS_SEC 1
J 0
(-4475 1075);
PAINT MONO (-4475 1075);
DISPLAY INVISIBLE (-4475 1075);
FORCEADD CAP_A..1
(-4275 875);
FORCEPROP 1 LASTPIN (-4275 775) $PN 2
J 0
(-4265 755);
DISPLAY 0.617021 (-4265 755);
PAINT ORANGE (-4265 755);
FORCEPROP 1 LAST TOLERANCE 10%
J 0
(-4225 825);
DISPLAY 0.617021 (-4225 825);
PAINT SKYBLUE (-4225 825);
FORCEPROP 1 LAST VOLTAGE 16V
J 0
(-4225 875);
DISPLAY 0.617021 (-4225 875);
PAINT SKYBLUE (-4225 875);
FORCEPROP 1 LAST MATERIAL X7R
J 0
(-4225 775);
DISPLAY 0.617021 (-4225 775);
PAINT SKYBLUE (-4225 775);
FORCEPROP 1 LASTPIN (-4275 975) $PN 1
J 0
(-4265 955);
DISPLAY 0.617021 (-4265 955);
PAINT ORANGE (-4265 955);
FORCEPROP 1 LAST PACK_TYPE 0402V
J 0
(-4225 675);
DISPLAY 0.617021 (-4225 675);
PAINT SKYBLUE (-4225 675);
FORCEPROP 1 LAST VALUE 0.1UF
J 0
(-4225 925);
DISPLAY 0.617021 (-4225 925);
PAINT SKYBLUE (-4225 925);
FORCEPROP 1 LAST PART_NUMBER A36096-030
J 0
(-4225 725);
DISPLAY 0.617021 (-4225 725);
PAINT BLUE (-4225 725);
FORCEPROP 1 LAST LOCATION C1R14
J 0
(-4225 975);
DISPLAY 0.617021 (-4225 975);
PAINT AQUA (-4225 975);
FORCEPROP 2 LAST CDS_LOCATION C1R14
J 0
(-4225 975);
DISPLAY 0.617021 (-4225 975);
PAINT AQUA (-4225 975);
DISPLAY INVISIBLE (-4225 975);
FORCEPROP 2 LAST CDS_LIB dev_discrete
J 0
(-4275 875);
PAINT ORANGE (-4275 875);
DISPLAY INVISIBLE (-4275 875);
FORCEPROP 2 LAST $SEC 1
J 0
(-4225 1075);
PAINT MONO (-4225 1075);
DISPLAY INVISIBLE (-4225 1075);
FORCEPROP 2 LAST CDS_SEC 1
J 0
(-4225 1075);
PAINT MONO (-4225 1075);
DISPLAY INVISIBLE (-4225 1075);
FORCEPROP 2 LAST BOM_COST NT_GBE_BASE
J 0
(-4225 1075);
DISPLAY 1.021277 (-4225 1075);
PAINT ORANGE (-4225 1075);
DISPLAY INVISIBLE (-4225 1075);
FORCEPROP 2 LAST ROOM NIC_SPRV
J 0
(-4225 1025);
DISPLAY 1.021277 (-4225 1025);
PAINT ORANGE (-4225 1025);
DISPLAY INVISIBLE (-4225 1025);
FORCEPROP 1 LAST PATH I145
J 0
(-4225 1025);
DISPLAY 0.978723 (-4225 1025);
PAINT WHITE (-4225 1025);
DISPLAY INVISIBLE (-4225 1025);
FORCEADD CAP_A..1
(-4025 875);
FORCEPROP 1 LASTPIN (-4025 775) $PN 2
J 0
(-4015 755);
DISPLAY 0.617021 (-4015 755);
PAINT ORANGE (-4015 755);
FORCEPROP 1 LAST TOLERANCE 10%
J 0
(-3975 825);
DISPLAY 0.617021 (-3975 825);
PAINT SKYBLUE (-3975 825);
FORCEPROP 1 LAST VOLTAGE 16V
J 0
(-3975 875);
DISPLAY 0.617021 (-3975 875);
PAINT SKYBLUE (-3975 875);
FORCEPROP 1 LAST MATERIAL X7R
J 0
(-3975 775);
DISPLAY 0.617021 (-3975 775);
PAINT SKYBLUE (-3975 775);
FORCEPROP 1 LASTPIN (-4025 975) $PN 1
J 0
(-4015 955);
DISPLAY 0.617021 (-4015 955);
PAINT ORANGE (-4015 955);
FORCEPROP 1 LAST PACK_TYPE 0402V
J 0
(-3975 675);
DISPLAY 0.617021 (-3975 675);
PAINT SKYBLUE (-3975 675);
FORCEPROP 1 LAST VALUE 0.1UF
J 0
(-3975 925);
DISPLAY 0.617021 (-3975 925);
PAINT SKYBLUE (-3975 925);
FORCEPROP 1 LAST PART_NUMBER A36096-030
J 0
(-3975 725);
DISPLAY 0.617021 (-3975 725);
PAINT BLUE (-3975 725);
FORCEPROP 1 LAST LOCATION C1R21
J 0
(-3975 975);
DISPLAY 0.617021 (-3975 975);
PAINT AQUA (-3975 975);
FORCEPROP 2 LAST CDS_LOCATION C1R21
J 0
(-3975 975);
DISPLAY 0.617021 (-3975 975);
PAINT AQUA (-3975 975);
DISPLAY INVISIBLE (-3975 975);
FORCEPROP 2 LAST CDS_LIB dev_discrete
J 0
(-4025 875);
PAINT ORANGE (-4025 875);
DISPLAY INVISIBLE (-4025 875);
FORCEPROP 2 LAST $SEC 1
J 0
(-3975 1075);
PAINT MONO (-3975 1075);
DISPLAY INVISIBLE (-3975 1075);
FORCEPROP 2 LAST CDS_SEC 1
J 0
(-3975 1075);
PAINT MONO (-3975 1075);
DISPLAY INVISIBLE (-3975 1075);
FORCEPROP 2 LAST BOM_COST NT_GBE_BASE
J 0
(-3975 1075);
DISPLAY 1.021277 (-3975 1075);
PAINT ORANGE (-3975 1075);
DISPLAY INVISIBLE (-3975 1075);
FORCEPROP 2 LAST ROOM NIC_SPRV
J 0
(-3975 1025);
DISPLAY 1.021277 (-3975 1025);
PAINT ORANGE (-3975 1025);
DISPLAY INVISIBLE (-3975 1025);
FORCEPROP 1 LAST PATH I146
J 0
(-3975 1025);
DISPLAY 0.978723 (-3975 1025);
PAINT WHITE (-3975 1025);
DISPLAY INVISIBLE (-3975 1025);
FORCEADD GND..1
(-5275 575);
FORCEPROP 3 LASTPIN (-5275 625) SIG_NAME GND\g
J 0
(-5265 635);
DISPLAY 0.659574 (-5265 635);
PAINT MONO (-5265 635);
DISPLAY INVISIBLE (-5265 635);
FORCEPROP 1 LAST BODY_TYPE PLUMBING
J 0
(-5320 532);
DISPLAY 0.340426 (-5320 532);
PAINT GREEN (-5320 532);
DISPLAY INVISIBLE (-5320 532);
FORCEPROP 2 LAST CDS_LIB mstr_symbols
J 0
(-5275 575);
PAINT ORANGE (-5275 575);
DISPLAY INVISIBLE (-5275 575);
FORCEPROP 1 LAST VOLTAGE 0.0V
J 0
(-5320 532);
DISPLAY 0.340426 (-5320 532);
PAINT SKYBLUE (-5320 532);
DISPLAY INVISIBLE (-5320 532);
FORCEPROP 1 LAST HDL_POWER GND
J 0
(-5275 725);
DISPLAY 0.872340 (-5275 725);
PAINT GREEN (-5275 725);
DISPLAY INVISIBLE (-5275 725);
FORCEPROP 1 LAST SIZE 1B
J 0
(-5200 525);
DISPLAY 0.872340 (-5200 525);
PAINT AQUA (-5200 525);
DISPLAY INVISIBLE (-5200 525);
FORCEPROP 1 LAST PATH I147
J 0
(-5200 575);
DISPLAY 0.872340 (-5200 575);
PAINT AQUA (-5200 575);
DISPLAY INVISIBLE (-5200 575);
FORCEADD CAP_A..1
(-2325 875);
FORCEPROP 1 LASTPIN (-2325 775) $PN 2
J 0
(-2315 755);
DISPLAY 0.617021 (-2315 755);
PAINT ORANGE (-2315 755);
FORCEPROP 1 LASTPIN (-2325 975) $PN 1
J 0
(-2315 955);
DISPLAY 0.617021 (-2315 955);
PAINT ORANGE (-2315 955);
FORCEPROP 1 LAST MATERIAL X7R
J 0
(-2275 775);
DISPLAY 0.617021 (-2275 775);
PAINT SKYBLUE (-2275 775);
FORCEPROP 1 LAST VOLTAGE 16V
J 0
(-2275 875);
DISPLAY 0.617021 (-2275 875);
PAINT SKYBLUE (-2275 875);
FORCEPROP 1 LAST PACK_TYPE 0402V
J 0
(-2275 675);
DISPLAY 0.617021 (-2275 675);
PAINT SKYBLUE (-2275 675);
FORCEPROP 1 LAST TOLERANCE 10%
J 0
(-2275 825);
DISPLAY 0.617021 (-2275 825);
PAINT SKYBLUE (-2275 825);
FORCEPROP 1 LAST VALUE 0.1UF
J 0
(-2275 925);
DISPLAY 0.617021 (-2275 925);
PAINT SKYBLUE (-2275 925);
FORCEPROP 1 LAST LOCATION C1R26
J 0
(-2275 975);
DISPLAY 0.617021 (-2275 975);
PAINT AQUA (-2275 975);
FORCEPROP 1 LAST PART_NUMBER A36096-030
J 0
(-2275 725);
DISPLAY 0.617021 (-2275 725);
PAINT BLUE (-2275 725);
FORCEPROP 2 LAST CDS_LIB dev_discrete
J 0
(-2325 875);
PAINT ORANGE (-2325 875);
DISPLAY INVISIBLE (-2325 875);
FORCEPROP 2 LAST CDS_LOCATION C1R26
J 0
(-2275 975);
DISPLAY 0.617021 (-2275 975);
PAINT AQUA (-2275 975);
DISPLAY INVISIBLE (-2275 975);
FORCEPROP 2 LAST $SEC 1
J 0
(-2275 1075);
PAINT MONO (-2275 1075);
DISPLAY INVISIBLE (-2275 1075);
FORCEPROP 2 LAST CDS_SEC 1
J 0
(-2275 1075);
PAINT MONO (-2275 1075);
DISPLAY INVISIBLE (-2275 1075);
FORCEPROP 2 LAST BOM_COST NT_GBE_BASE
J 0
(-2275 1075);
DISPLAY 1.021277 (-2275 1075);
PAINT ORANGE (-2275 1075);
DISPLAY INVISIBLE (-2275 1075);
FORCEPROP 2 LAST ROOM NIC_SPRV
J 0
(-2275 1025);
DISPLAY 1.021277 (-2275 1025);
PAINT ORANGE (-2275 1025);
DISPLAY INVISIBLE (-2275 1025);
FORCEPROP 1 LAST PATH I149
J 0
(-2275 1025);
DISPLAY 0.978723 (-2275 1025);
PAINT WHITE (-2275 1025);
DISPLAY INVISIBLE (-2275 1025);
FORCEADD CAP_A..1
(-2575 875);
FORCEPROP 1 LASTPIN (-2575 775) $PN 2
J 0
(-2565 755);
DISPLAY 0.617021 (-2565 755);
PAINT ORANGE (-2565 755);
FORCEPROP 1 LASTPIN (-2575 975) $PN 1
J 0
(-2565 955);
DISPLAY 0.617021 (-2565 955);
PAINT ORANGE (-2565 955);
FORCEPROP 1 LAST PACK_TYPE 0402V
J 0
(-2525 675);
DISPLAY 0.617021 (-2525 675);
PAINT SKYBLUE (-2525 675);
FORCEPROP 1 LAST LOCATION C1R29
J 0
(-2525 975);
DISPLAY 0.617021 (-2525 975);
PAINT AQUA (-2525 975);
FORCEPROP 1 LAST VALUE 0.1UF
J 0
(-2525 925);
DISPLAY 0.617021 (-2525 925);
PAINT SKYBLUE (-2525 925);
FORCEPROP 1 LAST TOLERANCE 10%
J 0
(-2525 825);
DISPLAY 0.617021 (-2525 825);
PAINT SKYBLUE (-2525 825);
FORCEPROP 1 LAST VOLTAGE 16V
J 0
(-2525 875);
DISPLAY 0.617021 (-2525 875);
PAINT SKYBLUE (-2525 875);
FORCEPROP 1 LAST MATERIAL X7R
J 0
(-2525 775);
DISPLAY 0.617021 (-2525 775);
PAINT SKYBLUE (-2525 775);
FORCEPROP 1 LAST PART_NUMBER A36096-030
J 0
(-2525 725);
DISPLAY 0.617021 (-2525 725);
PAINT BLUE (-2525 725);
FORCEPROP 2 LAST CDS_LIB dev_discrete
J 0
(-2575 875);
PAINT ORANGE (-2575 875);
DISPLAY INVISIBLE (-2575 875);
FORCEPROP 2 LAST CDS_LOCATION C1R29
J 0
(-2525 975);
DISPLAY 0.617021 (-2525 975);
PAINT AQUA (-2525 975);
DISPLAY INVISIBLE (-2525 975);
FORCEPROP 2 LAST $SEC 1
J 0
(-2525 1075);
PAINT MONO (-2525 1075);
DISPLAY INVISIBLE (-2525 1075);
FORCEPROP 2 LAST CDS_SEC 1
J 0
(-2525 1075);
PAINT MONO (-2525 1075);
DISPLAY INVISIBLE (-2525 1075);
FORCEPROP 2 LAST BOM_COST NT_GBE_BASE
J 0
(-2525 1075);
DISPLAY 1.021277 (-2525 1075);
PAINT ORANGE (-2525 1075);
DISPLAY INVISIBLE (-2525 1075);
FORCEPROP 2 LAST ROOM NIC_SPRV
J 0
(-2525 1025);
DISPLAY 1.021277 (-2525 1025);
PAINT ORANGE (-2525 1025);
DISPLAY INVISIBLE (-2525 1025);
FORCEPROP 1 LAST PATH I150
J 0
(-2525 1025);
DISPLAY 0.978723 (-2525 1025);
PAINT WHITE (-2525 1025);
DISPLAY INVISIBLE (-2525 1025);
FORCEADD CAP_A..1
(-2825 875);
FORCEPROP 1 LAST PACK_TYPE 0402V
J 0
(-2775 675);
DISPLAY 0.617021 (-2775 675);
PAINT SKYBLUE (-2775 675);
FORCEPROP 1 LASTPIN (-2825 775) $PN 2
J 0
(-2815 755);
DISPLAY 0.617021 (-2815 755);
PAINT ORANGE (-2815 755);
FORCEPROP 1 LAST LOCATION C1R19
J 0
(-2775 975);
DISPLAY 0.617021 (-2775 975);
PAINT AQUA (-2775 975);
FORCEPROP 1 LAST VALUE 0.1UF
J 0
(-2775 925);
DISPLAY 0.617021 (-2775 925);
PAINT SKYBLUE (-2775 925);
FORCEPROP 1 LAST TOLERANCE 10%
J 0
(-2775 825);
DISPLAY 0.617021 (-2775 825);
PAINT SKYBLUE (-2775 825);
FORCEPROP 1 LAST VOLTAGE 16V
J 0
(-2775 875);
DISPLAY 0.617021 (-2775 875);
PAINT SKYBLUE (-2775 875);
FORCEPROP 1 LAST MATERIAL X7R
J 0
(-2775 775);
DISPLAY 0.617021 (-2775 775);
PAINT SKYBLUE (-2775 775);
FORCEPROP 1 LASTPIN (-2825 975) $PN 1
J 0
(-2815 955);
DISPLAY 0.617021 (-2815 955);
PAINT ORANGE (-2815 955);
FORCEPROP 1 LAST PART_NUMBER A36096-030
J 0
(-2775 725);
DISPLAY 0.617021 (-2775 725);
PAINT BLUE (-2775 725);
FORCEPROP 2 LAST CDS_LIB dev_discrete
J 0
(-2825 875);
PAINT ORANGE (-2825 875);
DISPLAY INVISIBLE (-2825 875);
FORCEPROP 2 LAST CDS_LOCATION C1R19
J 0
(-2775 975);
DISPLAY 0.617021 (-2775 975);
PAINT AQUA (-2775 975);
DISPLAY INVISIBLE (-2775 975);
FORCEPROP 2 LAST $SEC 1
J 0
(-2775 1075);
PAINT MONO (-2775 1075);
DISPLAY INVISIBLE (-2775 1075);
FORCEPROP 2 LAST CDS_SEC 1
J 0
(-2775 1075);
PAINT MONO (-2775 1075);
DISPLAY INVISIBLE (-2775 1075);
FORCEPROP 2 LAST BOM_COST NT_GBE_BASE
J 0
(-2775 1075);
DISPLAY 1.021277 (-2775 1075);
PAINT ORANGE (-2775 1075);
DISPLAY INVISIBLE (-2775 1075);
FORCEPROP 2 LAST ROOM NIC_SPRV
J 0
(-2775 1025);
DISPLAY 1.021277 (-2775 1025);
PAINT ORANGE (-2775 1025);
DISPLAY INVISIBLE (-2775 1025);
FORCEPROP 1 LAST PATH I151
J 0
(-2775 1025);
DISPLAY 0.978723 (-2775 1025);
PAINT WHITE (-2775 1025);
DISPLAY INVISIBLE (-2775 1025);
FORCEADD CAP_A..1
(-3075 875);
FORCEPROP 1 LAST PACK_TYPE 0402V
J 0
(-3025 675);
DISPLAY 0.617021 (-3025 675);
PAINT SKYBLUE (-3025 675);
FORCEPROP 1 LASTPIN (-3075 775) $PN 2
J 0
(-3065 755);
DISPLAY 0.617021 (-3065 755);
PAINT ORANGE (-3065 755);
FORCEPROP 1 LAST LOCATION C1R31
J 0
(-3025 975);
DISPLAY 0.617021 (-3025 975);
PAINT AQUA (-3025 975);
FORCEPROP 1 LAST VALUE 0.1UF
J 0
(-3025 925);
DISPLAY 0.617021 (-3025 925);
PAINT SKYBLUE (-3025 925);
FORCEPROP 1 LAST TOLERANCE 10%
J 0
(-3025 825);
DISPLAY 0.617021 (-3025 825);
PAINT SKYBLUE (-3025 825);
FORCEPROP 1 LAST VOLTAGE 16V
J 0
(-3025 875);
DISPLAY 0.617021 (-3025 875);
PAINT SKYBLUE (-3025 875);
FORCEPROP 1 LAST MATERIAL X7R
J 0
(-3025 775);
DISPLAY 0.617021 (-3025 775);
PAINT SKYBLUE (-3025 775);
FORCEPROP 1 LASTPIN (-3075 975) $PN 1
J 0
(-3065 955);
DISPLAY 0.617021 (-3065 955);
PAINT ORANGE (-3065 955);
FORCEPROP 1 LAST PART_NUMBER A36096-030
J 0
(-3025 725);
DISPLAY 0.617021 (-3025 725);
PAINT BLUE (-3025 725);
FORCEPROP 2 LAST CDS_LIB dev_discrete
J 0
(-3075 875);
PAINT ORANGE (-3075 875);
DISPLAY INVISIBLE (-3075 875);
FORCEPROP 2 LAST $SEC 1
J 0
(-3025 1075);
PAINT MONO (-3025 1075);
DISPLAY INVISIBLE (-3025 1075);
FORCEPROP 2 LAST CDS_SEC 1
J 0
(-3025 1075);
PAINT MONO (-3025 1075);
DISPLAY INVISIBLE (-3025 1075);
FORCEPROP 2 LAST BOM_COST NT_GBE_BASE
J 0
(-3025 1075);
DISPLAY 1.021277 (-3025 1075);
PAINT ORANGE (-3025 1075);
DISPLAY INVISIBLE (-3025 1075);
FORCEPROP 2 LAST ROOM NIC_SPRV
J 0
(-3025 1025);
DISPLAY 1.021277 (-3025 1025);
PAINT ORANGE (-3025 1025);
DISPLAY INVISIBLE (-3025 1025);
FORCEPROP 1 LAST PATH I152
J 0
(-3025 1025);
DISPLAY 0.978723 (-3025 1025);
PAINT WHITE (-3025 1025);
DISPLAY INVISIBLE (-3025 1025);
FORCEADD CAP..1
(-3325 875);
FORCEPROP 1 LAST PACK_TYPE 0603
J 0
(-3275 675);
DISPLAY 0.617021 (-3275 675);
PAINT SKYBLUE (-3275 675);
FORCEPROP 1 LASTPIN (-3325 775) $PN 2
J 0
(-3315 755);
DISPLAY 0.617021 (-3315 755);
PAINT ORANGE (-3315 755);
FORCEPROP 1 LASTPIN (-3325 975) $PN 1
J 0
(-3315 955);
DISPLAY 0.617021 (-3315 955);
PAINT ORANGE (-3315 955);
FORCEPROP 1 LAST TOLERANCE 20%
J 0
(-3275 825);
DISPLAY 0.617021 (-3275 825);
PAINT SKYBLUE (-3275 825);
FORCEPROP 1 LAST VALUE 10UF
J 0
(-3275 925);
DISPLAY 0.617021 (-3275 925);
PAINT SKYBLUE (-3275 925);
FORCEPROP 1 LAST LOCATION C1R17
J 0
(-3275 975);
DISPLAY 0.617021 (-3275 975);
PAINT AQUA (-3275 975);
FORCEPROP 1 LAST MATERIAL X6S
J 0
(-3275 775);
DISPLAY 0.617021 (-3275 775);
PAINT SKYBLUE (-3275 775);
FORCEPROP 1 LAST VOLTAGE 6.3V
J 0
(-3275 875);
DISPLAY 0.617021 (-3275 875);
PAINT SKYBLUE (-3275 875);
FORCEPROP 1 LAST PART_NUMBER E15431-002
J 0
(-3275 725);
DISPLAY 0.617021 (-3275 725);
PAINT BLUE (-3275 725);
FORCEPROP 2 LAST CDS_LOCATION C1R17
J 0
(-3275 975);
DISPLAY 0.617021 (-3275 975);
PAINT AQUA (-3275 975);
DISPLAY INVISIBLE (-3275 975);
FORCEPROP 2 LAST CDS_LIB mstr_discrete
J 0
(-3325 875);
PAINT ORANGE (-3325 875);
DISPLAY INVISIBLE (-3325 875);
FORCEPROP 2 LAST $SEC 1
J 0
(-3275 1075);
PAINT MONO (-3275 1075);
DISPLAY INVISIBLE (-3275 1075);
FORCEPROP 2 LAST CDS_SEC 1
J 0
(-3275 1075);
PAINT MONO (-3275 1075);
DISPLAY INVISIBLE (-3275 1075);
FORCEPROP 2 LAST BOM_COST NT_GBE_BASE
J 0
(-3275 1075);
DISPLAY 1.021277 (-3275 1075);
PAINT ORANGE (-3275 1075);
DISPLAY INVISIBLE (-3275 1075);
FORCEPROP 2 LAST ROOM NIC_SPRV
J 0
(-3275 1025);
DISPLAY 1.021277 (-3275 1025);
PAINT ORANGE (-3275 1025);
DISPLAY INVISIBLE (-3275 1025);
FORCEPROP 1 LAST PATH I153
J 0
(-3275 1025);
DISPLAY 0.978723 (-3275 1025);
PAINT WHITE (-3275 1025);
DISPLAY INVISIBLE (-3275 1025);
FORCEADD P1V5_LAN..1
(-3575 1175);
FORCEPROP 3 LASTPIN (-3575 1125) SIG_NAME P1V5_LAN\g
J 0
(-3565 1135);
DISPLAY 0.659574 (-3565 1135);
PAINT MONO (-3565 1135);
DISPLAY INVISIBLE (-3565 1135);
FORCEPROP 1 LAST BODY_TYPE PLUMBING
J 0
(-3620 1132);
DISPLAY 0.340426 (-3620 1132);
PAINT GREEN (-3620 1132);
DISPLAY INVISIBLE (-3620 1132);
FORCEPROP 1 LAST VOLTAGE 1.5V
J 0
(-3620 1132);
DISPLAY 0.340426 (-3620 1132);
PAINT SKYBLUE (-3620 1132);
DISPLAY INVISIBLE (-3620 1132);
FORCEPROP 2 LAST CDS_LIB mstr_symbols
J 0
(-3575 1175);
PAINT ORANGE (-3575 1175);
DISPLAY INVISIBLE (-3575 1175);
FORCEPROP 1 LAST PATH I154
J 0
(-3525 1200);
DISPLAY 0.872340 (-3525 1200);
PAINT AQUA (-3525 1200);
DISPLAY INVISIBLE (-3525 1200);
FORCEPROP 1 LAST HDL_POWER P1V5_LAN
J 1
(-3575 1225);
DISPLAY 0.872340 (-3575 1225);
PAINT GREEN (-3575 1225);
DISPLAY INVISIBLE (-3575 1225);
FORCEADD CAP..1
(-3575 875);
FORCEPROP 1 LAST PACK_TYPE 1210
J 0
(-3525 675);
DISPLAY 0.617021 (-3525 675);
PAINT SKYBLUE (-3525 675);
FORCEPROP 1 LASTPIN (-3575 775) $PN 2
J 0
(-3565 755);
DISPLAY 0.617021 (-3565 755);
PAINT ORANGE (-3565 755);
FORCEPROP 1 LASTPIN (-3575 975) $PN 1
J 0
(-3565 955);
DISPLAY 0.617021 (-3565 955);
PAINT ORANGE (-3565 955);
FORCEPROP 1 LAST VOLTAGE 16V
J 0
(-3525 875);
DISPLAY 0.617021 (-3525 875);
PAINT SKYBLUE (-3525 875);
FORCEPROP 1 LAST TOLERANCE 20%
J 0
(-3525 825);
DISPLAY 0.617021 (-3525 825);
PAINT SKYBLUE (-3525 825);
FORCEPROP 1 LAST VALUE 47UF
J 0
(-3525 925);
DISPLAY 0.617021 (-3525 925);
PAINT SKYBLUE (-3525 925);
FORCEPROP 1 LAST LOCATION C9E6
J 0
(-3525 975);
DISPLAY 0.617021 (-3525 975);
PAINT AQUA (-3525 975);
FORCEPROP 1 LAST MATERIAL EMPTY
J 0
(-3525 775);
DISPLAY 0.617021 (-3525 775);
PAINT RED (-3525 775);
FORCEPROP 1 LAST PART_NUMBER D38464-007
J 0
(-3525 725);
DISPLAY 0.617021 (-3525 725);
PAINT BLUE (-3525 725);
FORCEPROP 2 LAST CDS_LIB mstr_discrete
J 0
(-3575 875);
PAINT ORANGE (-3575 875);
DISPLAY INVISIBLE (-3575 875);
FORCEPROP 2 LAST CDS_LOCATION C9E6
J 0
(-3525 975);
DISPLAY 0.617021 (-3525 975);
PAINT AQUA (-3525 975);
DISPLAY INVISIBLE (-3525 975);
FORCEPROP 2 LAST BOM_COST NT_GBE_BASE
J 0
(-3525 1075);
DISPLAY 1.021277 (-3525 1075);
PAINT ORANGE (-3525 1075);
DISPLAY INVISIBLE (-3525 1075);
FORCEPROP 2 LAST CDS_SEC 1
J 0
(-3525 1075);
PAINT MONO (-3525 1075);
DISPLAY INVISIBLE (-3525 1075);
FORCEPROP 2 LAST $SEC 1
J 0
(-3525 1075);
PAINT MONO (-3525 1075);
DISPLAY INVISIBLE (-3525 1075);
FORCEPROP 1 LAST PATH I155
J 0
(-3525 1025);
DISPLAY 0.978723 (-3525 1025);
PAINT WHITE (-3525 1025);
DISPLAY INVISIBLE (-3525 1025);
FORCEPROP 2 LAST ROOM NIC_SPRV
J 0
(-3525 1025);
DISPLAY 1.021277 (-3525 1025);
PAINT ORANGE (-3525 1025);
DISPLAY INVISIBLE (-3525 1025);
FORCEADD GND..1
(-3575 575);
FORCEPROP 3 LASTPIN (-3575 625) SIG_NAME GND\g
J 0
(-3565 635);
DISPLAY 0.659574 (-3565 635);
PAINT MONO (-3565 635);
DISPLAY INVISIBLE (-3565 635);
FORCEPROP 1 LAST BODY_TYPE PLUMBING
J 0
(-3620 532);
DISPLAY 0.340426 (-3620 532);
PAINT GREEN (-3620 532);
DISPLAY INVISIBLE (-3620 532);
FORCEPROP 1 LAST VOLTAGE 0.0V
J 0
(-3620 532);
DISPLAY 0.340426 (-3620 532);
PAINT SKYBLUE (-3620 532);
DISPLAY INVISIBLE (-3620 532);
FORCEPROP 1 LAST PATH I156
J 0
(-3500 575);
DISPLAY 0.872340 (-3500 575);
PAINT AQUA (-3500 575);
DISPLAY INVISIBLE (-3500 575);
FORCEPROP 1 LAST SIZE 1B
J 0
(-3500 525);
DISPLAY 0.872340 (-3500 525);
PAINT AQUA (-3500 525);
DISPLAY INVISIBLE (-3500 525);
FORCEPROP 2 LAST CDS_LIB mstr_symbols
J 0
(-3575 575);
PAINT ORANGE (-3575 575);
DISPLAY INVISIBLE (-3575 575);
FORCEPROP 1 LAST HDL_POWER GND
J 0
(-3575 725);
DISPLAY 0.872340 (-3575 725);
PAINT GREEN (-3575 725);
DISPLAY INVISIBLE (-3575 725);
FORCEADD CAP_A..1
(-350 875);
FORCEPROP 1 LASTPIN (-350 775) $PN 2
J 0
(-340 755);
DISPLAY 0.617021 (-340 755);
PAINT ORANGE (-340 755);
FORCEPROP 1 LASTPIN (-350 975) $PN 1
J 0
(-340 955);
DISPLAY 0.617021 (-340 955);
PAINT ORANGE (-340 955);
FORCEPROP 1 LAST VALUE 0.1UF
J 0
(-300 925);
DISPLAY 0.617021 (-300 925);
PAINT SKYBLUE (-300 925);
FORCEPROP 1 LAST TOLERANCE 10%
J 0
(-300 825);
DISPLAY 0.617021 (-300 825);
PAINT SKYBLUE (-300 825);
FORCEPROP 1 LAST LOCATION C1R18
J 0
(-300 975);
DISPLAY 0.617021 (-300 975);
PAINT AQUA (-300 975);
FORCEPROP 1 LAST PART_NUMBER A36096-030
J 0
(-300 725);
DISPLAY 0.617021 (-300 725);
PAINT BLUE (-300 725);
FORCEPROP 1 LAST MATERIAL X7R
J 0
(-300 775);
DISPLAY 0.617021 (-300 775);
PAINT SKYBLUE (-300 775);
FORCEPROP 1 LAST VOLTAGE 16V
J 0
(-300 875);
DISPLAY 0.617021 (-300 875);
PAINT SKYBLUE (-300 875);
FORCEPROP 1 LAST PACK_TYPE 0402V
J 0
(-300 675);
DISPLAY 0.617021 (-300 675);
PAINT SKYBLUE (-300 675);
FORCEPROP 2 LAST CDS_LIB dev_discrete
J 0
(-350 875);
PAINT ORANGE (-350 875);
DISPLAY INVISIBLE (-350 875);
FORCEPROP 2 LAST CDS_LOCATION C1R18
J 0
(-300 975);
DISPLAY 0.617021 (-300 975);
PAINT AQUA (-300 975);
DISPLAY INVISIBLE (-300 975);
FORCEPROP 2 LAST $SEC 1
J 0
(-300 1075);
PAINT MONO (-300 1075);
DISPLAY INVISIBLE (-300 1075);
FORCEPROP 2 LAST CDS_SEC 1
J 0
(-300 1075);
PAINT MONO (-300 1075);
DISPLAY INVISIBLE (-300 1075);
FORCEPROP 2 LAST BOM_COST NT_GBE_BASE
J 0
(-300 1075);
DISPLAY 1.021277 (-300 1075);
PAINT ORANGE (-300 1075);
DISPLAY INVISIBLE (-300 1075);
FORCEPROP 2 LAST ROOM NIC_SPRV
J 0
(-300 1025);
DISPLAY 1.021277 (-300 1025);
PAINT ORANGE (-300 1025);
DISPLAY INVISIBLE (-300 1025);
FORCEPROP 1 LAST PATH I157
J 0
(-300 1025);
DISPLAY 0.978723 (-300 1025);
PAINT WHITE (-300 1025);
DISPLAY INVISIBLE (-300 1025);
FORCEADD CAP_A..1
(-600 875);
FORCEPROP 1 LASTPIN (-600 775) $PN 2
J 0
(-590 755);
DISPLAY 0.617021 (-590 755);
PAINT ORANGE (-590 755);
FORCEPROP 1 LASTPIN (-600 975) $PN 1
J 0
(-590 955);
DISPLAY 0.617021 (-590 955);
PAINT ORANGE (-590 955);
FORCEPROP 1 LAST MATERIAL X7R
J 0
(-550 775);
DISPLAY 0.617021 (-550 775);
PAINT SKYBLUE (-550 775);
FORCEPROP 1 LAST VOLTAGE 16V
J 0
(-550 875);
DISPLAY 0.617021 (-550 875);
PAINT SKYBLUE (-550 875);
FORCEPROP 1 LAST PACK_TYPE 0402V
J 0
(-550 675);
DISPLAY 0.617021 (-550 675);
PAINT SKYBLUE (-550 675);
FORCEPROP 1 LAST TOLERANCE 10%
J 0
(-550 825);
DISPLAY 0.617021 (-550 825);
PAINT SKYBLUE (-550 825);
FORCEPROP 1 LAST VALUE 0.1UF
J 0
(-550 925);
DISPLAY 0.617021 (-550 925);
PAINT SKYBLUE (-550 925);
FORCEPROP 1 LAST PART_NUMBER A36096-030
J 0
(-550 725);
DISPLAY 0.617021 (-550 725);
PAINT BLUE (-550 725);
FORCEPROP 1 LAST LOCATION C1T5
J 0
(-550 975);
DISPLAY 0.617021 (-550 975);
PAINT AQUA (-550 975);
FORCEPROP 2 LAST CDS_LOCATION C1T5
J 0
(-550 975);
DISPLAY 0.617021 (-550 975);
PAINT AQUA (-550 975);
DISPLAY INVISIBLE (-550 975);
FORCEPROP 2 LAST CDS_LIB dev_discrete
J 0
(-600 875);
PAINT ORANGE (-600 875);
DISPLAY INVISIBLE (-600 875);
FORCEPROP 2 LAST $SEC 1
J 0
(-550 1075);
PAINT MONO (-550 1075);
DISPLAY INVISIBLE (-550 1075);
FORCEPROP 2 LAST CDS_SEC 1
J 0
(-550 1075);
PAINT MONO (-550 1075);
DISPLAY INVISIBLE (-550 1075);
FORCEPROP 2 LAST BOM_COST NT_GBE_BASE
J 0
(-550 1075);
DISPLAY 1.021277 (-550 1075);
PAINT ORANGE (-550 1075);
DISPLAY INVISIBLE (-550 1075);
FORCEPROP 2 LAST ROOM NIC_SPRV
J 0
(-550 1025);
DISPLAY 1.021277 (-550 1025);
PAINT ORANGE (-550 1025);
DISPLAY INVISIBLE (-550 1025);
FORCEPROP 1 LAST PATH I158
J 0
(-550 1025);
DISPLAY 0.978723 (-550 1025);
PAINT WHITE (-550 1025);
DISPLAY INVISIBLE (-550 1025);
FORCEADD CAP_A..1
(-850 875);
FORCEPROP 1 LASTPIN (-850 775) $PN 2
J 0
(-840 755);
DISPLAY 0.617021 (-840 755);
PAINT ORANGE (-840 755);
FORCEPROP 1 LASTPIN (-850 975) $PN 1
J 0
(-840 955);
DISPLAY 0.617021 (-840 955);
PAINT ORANGE (-840 955);
FORCEPROP 1 LAST MATERIAL X7R
J 0
(-800 775);
DISPLAY 0.617021 (-800 775);
PAINT SKYBLUE (-800 775);
FORCEPROP 1 LAST VOLTAGE 16V
J 0
(-800 875);
DISPLAY 0.617021 (-800 875);
PAINT SKYBLUE (-800 875);
FORCEPROP 1 LAST PACK_TYPE 0402V
J 0
(-800 675);
DISPLAY 0.617021 (-800 675);
PAINT SKYBLUE (-800 675);
FORCEPROP 1 LAST TOLERANCE 10%
J 0
(-800 825);
DISPLAY 0.617021 (-800 825);
PAINT SKYBLUE (-800 825);
FORCEPROP 1 LAST VALUE 0.1UF
J 0
(-800 925);
DISPLAY 0.617021 (-800 925);
PAINT SKYBLUE (-800 925);
FORCEPROP 1 LAST LOCATION C1R24
J 0
(-800 975);
DISPLAY 0.617021 (-800 975);
PAINT AQUA (-800 975);
FORCEPROP 1 LAST PART_NUMBER A36096-030
J 0
(-800 725);
DISPLAY 0.617021 (-800 725);
PAINT BLUE (-800 725);
FORCEPROP 2 LAST CDS_LOCATION C1R24
J 0
(-800 975);
DISPLAY 0.617021 (-800 975);
PAINT AQUA (-800 975);
DISPLAY INVISIBLE (-800 975);
FORCEPROP 2 LAST CDS_LIB dev_discrete
J 0
(-850 875);
PAINT ORANGE (-850 875);
DISPLAY INVISIBLE (-850 875);
FORCEPROP 1 LAST PATH I159
J 0
(-800 1025);
DISPLAY 0.978723 (-800 1025);
PAINT WHITE (-800 1025);
DISPLAY INVISIBLE (-800 1025);
FORCEPROP 2 LAST ROOM NIC_SPRV
J 0
(-800 1025);
DISPLAY 1.021277 (-800 1025);
PAINT ORANGE (-800 1025);
DISPLAY INVISIBLE (-800 1025);
FORCEPROP 2 LAST BOM_COST NT_GBE_BASE
J 0
(-800 1075);
DISPLAY 1.021277 (-800 1075);
PAINT ORANGE (-800 1075);
DISPLAY INVISIBLE (-800 1075);
FORCEPROP 2 LAST CDS_SEC 1
J 0
(-800 1075);
PAINT MONO (-800 1075);
DISPLAY INVISIBLE (-800 1075);
FORCEPROP 2 LAST $SEC 1
J 0
(-800 1075);
PAINT MONO (-800 1075);
DISPLAY INVISIBLE (-800 1075);
FORCEADD CAP_A..1
(-1100 875);
FORCEPROP 1 LASTPIN (-1100 775) $PN 2
J 0
(-1090 755);
DISPLAY 0.617021 (-1090 755);
PAINT ORANGE (-1090 755);
FORCEPROP 1 LASTPIN (-1100 975) $PN 1
J 0
(-1090 955);
DISPLAY 0.617021 (-1090 955);
PAINT ORANGE (-1090 955);
FORCEPROP 1 LAST MATERIAL X7R
J 0
(-1050 775);
DISPLAY 0.617021 (-1050 775);
PAINT SKYBLUE (-1050 775);
FORCEPROP 1 LAST VOLTAGE 16V
J 0
(-1050 875);
DISPLAY 0.617021 (-1050 875);
PAINT SKYBLUE (-1050 875);
FORCEPROP 1 LAST PACK_TYPE 0402V
J 0
(-1050 675);
DISPLAY 0.617021 (-1050 675);
PAINT SKYBLUE (-1050 675);
FORCEPROP 1 LAST TOLERANCE 10%
J 0
(-1050 825);
DISPLAY 0.617021 (-1050 825);
PAINT SKYBLUE (-1050 825);
FORCEPROP 1 LAST VALUE 0.1UF
J 0
(-1050 925);
DISPLAY 0.617021 (-1050 925);
PAINT SKYBLUE (-1050 925);
FORCEPROP 1 LAST PART_NUMBER A36096-030
J 0
(-1050 725);
DISPLAY 0.617021 (-1050 725);
PAINT BLUE (-1050 725);
FORCEPROP 1 LAST LOCATION C1R15
J 0
(-1050 975);
DISPLAY 0.617021 (-1050 975);
PAINT AQUA (-1050 975);
FORCEPROP 2 LAST CDS_LOCATION C1R15
J 0
(-1050 975);
DISPLAY 0.617021 (-1050 975);
PAINT AQUA (-1050 975);
DISPLAY INVISIBLE (-1050 975);
FORCEPROP 2 LAST CDS_LIB dev_discrete
J 0
(-1100 875);
PAINT ORANGE (-1100 875);
DISPLAY INVISIBLE (-1100 875);
FORCEPROP 1 LAST PATH I160
J 0
(-1050 1025);
DISPLAY 0.978723 (-1050 1025);
PAINT WHITE (-1050 1025);
DISPLAY INVISIBLE (-1050 1025);
FORCEPROP 2 LAST ROOM NIC_SPRV
J 0
(-1050 1025);
DISPLAY 1.021277 (-1050 1025);
PAINT ORANGE (-1050 1025);
DISPLAY INVISIBLE (-1050 1025);
FORCEPROP 2 LAST BOM_COST NT_GBE_BASE
J 0
(-1050 1075);
DISPLAY 1.021277 (-1050 1075);
PAINT ORANGE (-1050 1075);
DISPLAY INVISIBLE (-1050 1075);
FORCEPROP 2 LAST CDS_SEC 1
J 0
(-1050 1075);
PAINT MONO (-1050 1075);
DISPLAY INVISIBLE (-1050 1075);
FORCEPROP 2 LAST $SEC 1
J 0
(-1050 1075);
PAINT MONO (-1050 1075);
DISPLAY INVISIBLE (-1050 1075);
FORCEADD CAP..1
(-1350 875);
FORCEPROP 1 LASTPIN (-1350 775) $PN 2
J 0
(-1340 755);
DISPLAY 0.617021 (-1340 755);
PAINT ORANGE (-1340 755);
FORCEPROP 1 LASTPIN (-1350 975) $PN 1
J 0
(-1340 955);
DISPLAY 0.617021 (-1340 955);
PAINT ORANGE (-1340 955);
FORCEPROP 1 LAST MATERIAL X6S
J 0
(-1300 775);
DISPLAY 0.617021 (-1300 775);
PAINT SKYBLUE (-1300 775);
FORCEPROP 1 LAST VOLTAGE 6.3V
J 0
(-1300 875);
DISPLAY 0.617021 (-1300 875);
PAINT SKYBLUE (-1300 875);
FORCEPROP 1 LAST PACK_TYPE 0603
J 0
(-1300 675);
DISPLAY 0.617021 (-1300 675);
PAINT SKYBLUE (-1300 675);
FORCEPROP 1 LAST TOLERANCE 20%
J 0
(-1300 825);
DISPLAY 0.617021 (-1300 825);
PAINT SKYBLUE (-1300 825);
FORCEPROP 1 LAST VALUE 10UF
J 0
(-1300 925);
DISPLAY 0.617021 (-1300 925);
PAINT SKYBLUE (-1300 925);
FORCEPROP 1 LAST LOCATION C1R16
J 0
(-1300 975);
DISPLAY 0.617021 (-1300 975);
PAINT AQUA (-1300 975);
FORCEPROP 1 LAST PART_NUMBER E15431-002
J 0
(-1300 725);
DISPLAY 0.617021 (-1300 725);
PAINT BLUE (-1300 725);
FORCEPROP 2 LAST CDS_LOCATION C1R16
J 0
(-1300 975);
DISPLAY 0.617021 (-1300 975);
PAINT AQUA (-1300 975);
DISPLAY INVISIBLE (-1300 975);
FORCEPROP 2 LAST CDS_LIB mstr_discrete
J 0
(-1350 875);
PAINT ORANGE (-1350 875);
DISPLAY INVISIBLE (-1350 875);
FORCEPROP 2 LAST BOM_COST NT_GBE_BASE
J 0
(-1300 1075);
DISPLAY 1.021277 (-1300 1075);
PAINT ORANGE (-1300 1075);
DISPLAY INVISIBLE (-1300 1075);
FORCEPROP 2 LAST CDS_SEC 1
J 0
(-1300 1075);
PAINT MONO (-1300 1075);
DISPLAY INVISIBLE (-1300 1075);
FORCEPROP 2 LAST $SEC 1
J 0
(-1300 1075);
PAINT MONO (-1300 1075);
DISPLAY INVISIBLE (-1300 1075);
FORCEPROP 1 LAST PATH I161
J 0
(-1300 1025);
DISPLAY 0.978723 (-1300 1025);
PAINT WHITE (-1300 1025);
DISPLAY INVISIBLE (-1300 1025);
FORCEPROP 2 LAST ROOM NIC_SPRV
J 0
(-1300 1025);
DISPLAY 1.021277 (-1300 1025);
PAINT ORANGE (-1300 1025);
DISPLAY INVISIBLE (-1300 1025);
FORCEADD P0V9_LAN..1
(-1925 1150);
FORCEPROP 3 LASTPIN (-1925 1100) SIG_NAME P0V9_LAN\g
J 0
(-1915 1110);
DISPLAY 0.659574 (-1915 1110);
PAINT MONO (-1915 1110);
DISPLAY INVISIBLE (-1915 1110);
FORCEPROP 1 LAST VOLTAGE 0.9V
J 0
(-1970 1107);
DISPLAY 0.340426 (-1970 1107);
PAINT SKYBLUE (-1970 1107);
DISPLAY INVISIBLE (-1970 1107);
FORCEPROP 2 LAST CDS_LIB mstr_symbols
J 0
(-1925 1150);
PAINT ORANGE (-1925 1150);
DISPLAY INVISIBLE (-1925 1150);
FORCEPROP 1 LAST BODY_TYPE PLUMBING
J 0
(-1970 1107);
DISPLAY 0.340426 (-1970 1107);
PAINT GREEN (-1970 1107);
DISPLAY INVISIBLE (-1970 1107);
FORCEPROP 1 LAST HDL_POWER P0V9_LAN
J 1
(-1925 1200);
DISPLAY 0.872340 (-1925 1200);
PAINT GREEN (-1925 1200);
DISPLAY INVISIBLE (-1925 1200);
FORCEPROP 1 LAST PATH I162
J 0
(-1875 1175);
DISPLAY 0.872340 (-1875 1175);
PAINT AQUA (-1875 1175);
DISPLAY INVISIBLE (-1875 1175);
FORCEADD CAP_A..1
(-1600 875);
FORCEPROP 1 LASTPIN (-1600 775) $PN 2
J 0
(-1590 755);
DISPLAY 0.617021 (-1590 755);
PAINT ORANGE (-1590 755);
FORCEPROP 1 LASTPIN (-1600 975) $PN 1
J 0
(-1590 955);
DISPLAY 0.617021 (-1590 955);
PAINT ORANGE (-1590 955);
FORCEPROP 1 LAST VOLTAGE 4V
J 0
(-1550 875);
DISPLAY 0.617021 (-1550 875);
PAINT SKYBLUE (-1550 875);
FORCEPROP 1 LAST PACK_TYPE 0603V
J 0
(-1550 675);
DISPLAY 0.617021 (-1550 675);
PAINT SKYBLUE (-1550 675);
FORCEPROP 1 LAST TOLERANCE 20%
J 0
(-1550 825);
DISPLAY 0.617021 (-1550 825);
PAINT SKYBLUE (-1550 825);
FORCEPROP 1 LAST VALUE 22.0UF
J 0
(-1550 925);
DISPLAY 0.617021 (-1550 925);
PAINT SKYBLUE (-1550 925);
FORCEPROP 1 LAST PART_NUMBER E15431-004
J 0
(-1550 725);
DISPLAY 0.617021 (-1550 725);
PAINT BLUE (-1550 725);
FORCEPROP 1 LAST LOCATION C9E1
J 0
(-1550 975);
DISPLAY 0.617021 (-1550 975);
PAINT AQUA (-1550 975);
FORCEPROP 1 LAST MATERIAL EMPTY
J 0
(-1550 775);
DISPLAY 0.617021 (-1550 775);
PAINT RED (-1550 775);
FORCEPROP 2 LAST CDS_LIB dev_discrete
J 0
(-1600 875);
PAINT ORANGE (-1600 875);
DISPLAY INVISIBLE (-1600 875);
FORCEPROP 2 LAST CDS_LOCATION C9E1
J 0
(-1550 975);
DISPLAY 0.617021 (-1550 975);
PAINT AQUA (-1550 975);
DISPLAY INVISIBLE (-1550 975);
FORCEPROP 2 LAST ROOM NIC_SPRV
J 0
(-1550 1025);
DISPLAY 1.021277 (-1550 1025);
PAINT ORANGE (-1550 1025);
DISPLAY INVISIBLE (-1550 1025);
FORCEPROP 1 LAST PATH I163
J 0
(-1550 1025);
DISPLAY 0.978723 (-1550 1025);
PAINT WHITE (-1550 1025);
DISPLAY INVISIBLE (-1550 1025);
FORCEPROP 2 LAST SEC_TYPE 0603V
J 0
(-1550 1075);
DISPLAY 1.021277 (-1550 1075);
PAINT ORANGE (-1550 1075);
DISPLAY INVISIBLE (-1550 1075);
FORCEPROP 2 LAST SEC 1
J 0
(-1550 1075);
DISPLAY 0.680851 (-1550 1075);
PAINT MONO (-1550 1075);
DISPLAY INVISIBLE (-1550 1075);
FORCEPROP 2 LAST BOM_COST NT_GBE_BASE
J 0
(-1550 1075);
DISPLAY 1.021277 (-1550 1075);
PAINT ORANGE (-1550 1075);
DISPLAY INVISIBLE (-1550 1075);
FORCEADD GND..1
(-1925 575);
FORCEPROP 3 LASTPIN (-1925 625) SIG_NAME GND\g
J 0
(-1915 635);
DISPLAY 0.659574 (-1915 635);
PAINT MONO (-1915 635);
DISPLAY INVISIBLE (-1915 635);
FORCEPROP 1 LAST VOLTAGE 0.0V
J 0
(-1970 532);
DISPLAY 0.340426 (-1970 532);
PAINT SKYBLUE (-1970 532);
DISPLAY INVISIBLE (-1970 532);
FORCEPROP 2 LAST CDS_LIB mstr_symbols
J 0
(-1925 575);
PAINT ORANGE (-1925 575);
DISPLAY INVISIBLE (-1925 575);
FORCEPROP 1 LAST BODY_TYPE PLUMBING
J 0
(-1970 532);
DISPLAY 0.340426 (-1970 532);
PAINT GREEN (-1970 532);
DISPLAY INVISIBLE (-1970 532);
FORCEPROP 1 LAST HDL_POWER GND
J 0
(-1925 725);
DISPLAY 0.872340 (-1925 725);
PAINT GREEN (-1925 725);
DISPLAY INVISIBLE (-1925 725);
FORCEPROP 1 LAST SIZE 1B
J 0
(-1850 525);
DISPLAY 0.872340 (-1850 525);
PAINT AQUA (-1850 525);
DISPLAY INVISIBLE (-1850 525);
FORCEPROP 1 LAST PATH I164
J 0
(-1850 575);
DISPLAY 0.872340 (-1850 575);
PAINT AQUA (-1850 575);
DISPLAY INVISIBLE (-1850 575);
FORCEADD OFFPAGE..1
(-6050 3125);
FORCEPROP 2 LAST $XR0 118 
J 0
(-6302 3125);
DISPLAY 0.638298 (-6302 3125);
PAINT MONO (-6302 3125);
FORCEPROP 1 LAST COMMENT_BODY TRUE
J 0
(-5925 3025);
DISPLAY 0.872340 (-5925 3025);
PAINT GREEN (-5925 3025);
DISPLAY INVISIBLE (-5925 3025);
FORCEPROP 1 LAST OFFPAGE TRUE
J 0
(-5725 3000);
DISPLAY 0.872340 (-5725 3000);
PAINT GREEN (-5725 3000);
DISPLAY INVISIBLE (-5725 3000);
FORCEPROP 2 LAST CDS_LIB mstr_standard
J 0
(-6050 3125);
PAINT ORANGE (-6050 3125);
DISPLAY INVISIBLE (-6050 3125);
FORCEPROP 2 LAST PATH I165
J 0
(-6000 3200);
DISPLAY 1.021277 (-6000 3200);
PAINT ORANGE (-6000 3200);
DISPLAY INVISIBLE (-6000 3200);
FORCEADD OFFPAGE..1
(-6050 3075);
FORCEPROP 2 LAST $XR0 139 
J 0
(-6302 3075);
DISPLAY 0.638298 (-6302 3075);
PAINT MONO (-6302 3075);
FORCEPROP 1 LAST COMMENT_BODY TRUE
J 0
(-5925 2975);
DISPLAY 0.872340 (-5925 2975);
PAINT GREEN (-5925 2975);
DISPLAY INVISIBLE (-5925 2975);
FORCEPROP 1 LAST OFFPAGE TRUE
J 0
(-5725 2950);
DISPLAY 0.872340 (-5725 2950);
PAINT GREEN (-5725 2950);
DISPLAY INVISIBLE (-5725 2950);
FORCEPROP 2 LAST CDS_LIB mstr_standard
J 0
(-6050 3075);
PAINT ORANGE (-6050 3075);
DISPLAY INVISIBLE (-6050 3075);
FORCEPROP 2 LAST PATH I166
J 0
(-6000 3150);
DISPLAY 1.021277 (-6000 3150);
PAINT ORANGE (-6000 3150);
DISPLAY INVISIBLE (-6000 3150);
FORCEADD OFFPAGE..1
(-6050 3025);
FORCEPROP 2 LAST $XR0 139 
J 0
(-6302 3025);
DISPLAY 0.638298 (-6302 3025);
PAINT MONO (-6302 3025);
FORCEPROP 2 LAST CDS_LIB mstr_standard
J 0
(-6050 3025);
PAINT ORANGE (-6050 3025);
DISPLAY INVISIBLE (-6050 3025);
FORCEPROP 1 LAST COMMENT_BODY TRUE
J 0
(-5925 2925);
DISPLAY 0.872340 (-5925 2925);
PAINT GREEN (-5925 2925);
DISPLAY INVISIBLE (-5925 2925);
FORCEPROP 1 LAST OFFPAGE TRUE
J 0
(-5725 2900);
DISPLAY 0.872340 (-5725 2900);
PAINT GREEN (-5725 2900);
DISPLAY INVISIBLE (-5725 2900);
FORCEPROP 2 LAST PATH I167
J 0
(-6000 3100);
DISPLAY 1.021277 (-6000 3100);
PAINT ORANGE (-6000 3100);
DISPLAY INVISIBLE (-6000 3100);
FORCEADD OFFPAGE..2
(-325 3600);
FORCEPROP 2 LAST $XR0 139 
J 0
(-136 3600);
DISPLAY 0.638298 (-136 3600);
PAINT MONO (-136 3600);
FORCEPROP 1 LAST COMMENT_BODY TRUE
J 0
(-370 3505);
DISPLAY 0.872340 (-370 3505);
PAINT GREEN (-370 3505);
DISPLAY INVISIBLE (-370 3505);
FORCEPROP 2 LAST CDS_LIB mstr_standard
J 0
(-325 3600);
PAINT ORANGE (-325 3600);
DISPLAY INVISIBLE (-325 3600);
FORCEPROP 2 LAST PATH I172
J 0
(-150 3675);
DISPLAY 1.021277 (-150 3675);
PAINT ORANGE (-150 3675);
DISPLAY INVISIBLE (-150 3675);
FORCEPROP 1 LAST OFFPAGE TRUE
J 0
(0 3475);
DISPLAY 0.872340 (0 3475);
PAINT GREEN (0 3475);
DISPLAY INVISIBLE (0 3475);
FORCEADD RES..2
(-900 3825);
FORCEPROP 1 LASTPIN (-900 3725) $PN 2
J 0
(-895 3735);
DISPLAY 0.617021 (-895 3735);
PAINT ORANGE (-895 3735);
FORCEPROP 1 LASTPIN (-900 3925) $PN 1
J 0
(-895 3887);
DISPLAY 0.617021 (-895 3887);
PAINT ORANGE (-895 3887);
FORCEPROP 1 LAST TOLERANCE 1%
J 0
(-855 3850);
DISPLAY 0.617021 (-855 3850);
PAINT SKYBLUE (-855 3850);
FORCEPROP 1 LAST WATTAGE 1/16W
J 0
(-860 3800);
DISPLAY 0.617021 (-860 3800);
PAINT SKYBLUE (-860 3800);
FORCEPROP 1 LAST MATERIAL CHIP
J 0
(-860 3750);
DISPLAY 0.617021 (-860 3750);
PAINT SKYBLUE (-860 3750);
FORCEPROP 1 LAST PACK_TYPE 0402
J 0
(-860 3650);
DISPLAY 0.617021 (-860 3650);
PAINT SKYBLUE (-860 3650);
FORCEPROP 1 LAST VALUE 3.32K
J 0
(-855 3900);
DISPLAY 0.617021 (-855 3900);
PAINT SKYBLUE (-855 3900);
FORCEPROP 1 LAST PART_NUMBER G21796-027
J 0
(-860 3700);
DISPLAY 0.617021 (-860 3700);
PAINT BLUE (-860 3700);
FORCEPROP 1 LAST LOCATION R9F5
J 0
(-855 3950);
DISPLAY 0.617021 (-855 3950);
PAINT AQUA (-855 3950);
FORCEPROP 2 LAST CDS_LIB mstr_discrete
J 0
(-900 3825);
PAINT ORANGE (-900 3825);
DISPLAY INVISIBLE (-900 3825);
FORCEPROP 2 LAST ROOM NIC_SPRV
J 0
(-850 4000);
DISPLAY 1.021277 (-850 4000);
PAINT ORANGE (-850 4000);
DISPLAY INVISIBLE (-850 4000);
FORCEPROP 1 LAST PATH I173
J 0
(-850 4000);
DISPLAY 0.978723 (-850 4000);
PAINT WHITE (-850 4000);
DISPLAY INVISIBLE (-850 4000);
FORCEPROP 2 LAST CDS_LOCATION R9F5
J 0
(-855 3950);
DISPLAY 0.617021 (-855 3950);
PAINT AQUA (-855 3950);
DISPLAY INVISIBLE (-855 3950);
FORCEPROP 2 LAST $SEC 1
J 0
(-850 4050);
PAINT MONO (-850 4050);
DISPLAY INVISIBLE (-850 4050);
FORCEPROP 2 LAST BOM_COST NT_GBE_BASE
J 0
(-850 4050);
DISPLAY 1.021277 (-850 4050);
PAINT ORANGE (-850 4050);
DISPLAY INVISIBLE (-850 4050);
FORCEPROP 2 LAST CDS_SEC 1
J 0
(-850 4050);
PAINT MONO (-850 4050);
DISPLAY INVISIBLE (-850 4050);
FORCEADD RES..2
(-900 3225);
FORCEPROP 1 LAST PACK_TYPE 0402
J 0
(-860 3050);
DISPLAY 0.617021 (-860 3050);
PAINT SKYBLUE (-860 3050);
FORCEPROP 1 LAST TOLERANCE 1%
J 0
(-855 3250);
DISPLAY 0.617021 (-855 3250);
PAINT SKYBLUE (-855 3250);
FORCEPROP 1 LASTPIN (-900 3125) $PN 2
J 0
(-895 3135);
DISPLAY 0.617021 (-895 3135);
PAINT ORANGE (-895 3135);
FORCEPROP 1 LASTPIN (-900 3325) $PN 1
J 0
(-895 3287);
DISPLAY 0.617021 (-895 3287);
PAINT ORANGE (-895 3287);
FORCEPROP 1 LAST WATTAGE 1/16W
J 0
(-860 3200);
DISPLAY 0.617021 (-860 3200);
PAINT SKYBLUE (-860 3200);
FORCEPROP 1 LAST MATERIAL CHIP
J 0
(-860 3150);
DISPLAY 0.617021 (-860 3150);
PAINT SKYBLUE (-860 3150);
FORCEPROP 1 LAST VALUE 4.99K
J 0
(-855 3300);
DISPLAY 0.617021 (-855 3300);
PAINT SKYBLUE (-855 3300);
FORCEPROP 1 LAST PART_NUMBER G21796-013
J 0
(-860 3100);
DISPLAY 0.617021 (-860 3100);
PAINT BLUE (-860 3100);
FORCEPROP 1 LAST LOCATION R9E23
J 0
(-855 3350);
DISPLAY 0.617021 (-855 3350);
PAINT AQUA (-855 3350);
FORCEPROP 2 LAST CDS_LIB mstr_discrete
J 0
(-900 3225);
PAINT ORANGE (-900 3225);
DISPLAY INVISIBLE (-900 3225);
FORCEPROP 2 LAST ROOM NIC_SPRV
J 0
(-850 3400);
DISPLAY 1.021277 (-850 3400);
PAINT ORANGE (-850 3400);
DISPLAY INVISIBLE (-850 3400);
FORCEPROP 1 LAST PATH I174
J 0
(-850 3400);
DISPLAY 0.978723 (-850 3400);
PAINT WHITE (-850 3400);
DISPLAY INVISIBLE (-850 3400);
FORCEPROP 2 LAST CDS_LOCATION R9E23
J 0
(-855 3350);
DISPLAY 0.617021 (-855 3350);
PAINT AQUA (-855 3350);
DISPLAY INVISIBLE (-855 3350);
FORCEPROP 2 LAST SEC_TYPE 0402
J 0
(-850 3450);
DISPLAY 1.021277 (-850 3450);
PAINT ORANGE (-850 3450);
DISPLAY INVISIBLE (-850 3450);
FORCEPROP 2 LAST BOM_COST NT_GBE_BASE
J 0
(-850 3450);
DISPLAY 1.021277 (-850 3450);
PAINT ORANGE (-850 3450);
DISPLAY INVISIBLE (-850 3450);
FORCEPROP 2 LAST SEC 1
J 0
(-850 3450);
DISPLAY 0.680851 (-850 3450);
PAINT MONO (-850 3450);
DISPLAY INVISIBLE (-850 3450);
FORCEADD OFFPAGE..2
(-475 3400);
FORCEPROP 2 LAST $XR0 139 
J 0
(-286 3400);
DISPLAY 0.638298 (-286 3400);
PAINT MONO (-286 3400);
FORCEPROP 1 LAST COMMENT_BODY TRUE
J 0
(-520 3305);
DISPLAY 0.872340 (-520 3305);
PAINT GREEN (-520 3305);
DISPLAY INVISIBLE (-520 3305);
FORCEPROP 2 LAST CDS_LIB mstr_standard
J 0
(-475 3400);
PAINT ORANGE (-475 3400);
DISPLAY INVISIBLE (-475 3400);
FORCEPROP 2 LAST PATH I175
J 0
(-300 3475);
DISPLAY 1.021277 (-300 3475);
PAINT ORANGE (-300 3475);
DISPLAY INVISIBLE (-300 3475);
FORCEPROP 1 LAST OFFPAGE TRUE
J 0
(-150 3275);
DISPLAY 0.872340 (-150 3275);
PAINT GREEN (-150 3275);
DISPLAY INVISIBLE (-150 3275);
FORCEADD GND..1
(-900 2950);
FORCEPROP 3 LASTPIN (-900 3000) SIG_NAME GND\g
J 0
(-890 3010);
DISPLAY 0.659574 (-890 3010);
PAINT MONO (-890 3010);
DISPLAY INVISIBLE (-890 3010);
FORCEPROP 1 LAST PATH I176
J 0
(-825 2950);
DISPLAY 0.872340 (-825 2950);
PAINT AQUA (-825 2950);
DISPLAY INVISIBLE (-825 2950);
FORCEPROP 1 LAST BODY_TYPE PLUMBING
J 0
(-945 2907);
DISPLAY 0.340426 (-945 2907);
PAINT GREEN (-945 2907);
DISPLAY INVISIBLE (-945 2907);
FORCEPROP 1 LAST SIZE 1B
J 0
(-825 2900);
DISPLAY 0.872340 (-825 2900);
PAINT AQUA (-825 2900);
DISPLAY INVISIBLE (-825 2900);
FORCEPROP 2 LAST CDS_LIB mstr_symbols
J 0
(-900 2950);
PAINT ORANGE (-900 2950);
DISPLAY INVISIBLE (-900 2950);
FORCEPROP 1 LAST VOLTAGE 0.0V
J 0
(-945 2907);
DISPLAY 0.340426 (-945 2907);
PAINT SKYBLUE (-945 2907);
DISPLAY INVISIBLE (-945 2907);
FORCEPROP 1 LAST HDL_POWER GND
J 0
(-900 3100);
DISPLAY 0.872340 (-900 3100);
PAINT GREEN (-900 3100);
DISPLAY INVISIBLE (-900 3100);
FORCEADD RES..2
(-7025 3125);
FORCEPROP 1 LASTPIN (-7025 3025) $PN 2
J 0
(-7020 3035);
DISPLAY 0.617021 (-7020 3035);
PAINT ORANGE (-7020 3035);
FORCEPROP 1 LAST PACK_TYPE 0402
J 0
(-6985 2950);
DISPLAY 0.617021 (-6985 2950);
PAINT SKYBLUE (-6985 2950);
FORCEPROP 1 LAST PART_NUMBER G21796-016
J 0
(-6985 3000);
DISPLAY 0.617021 (-6985 3000);
PAINT BLUE (-6985 3000);
FORCEPROP 1 LAST MATERIAL CHIP
J 0
(-6985 3050);
DISPLAY 0.617021 (-6985 3050);
PAINT SKYBLUE (-6985 3050);
FORCEPROP 1 LAST TOLERANCE 1%
J 0
(-6980 3150);
DISPLAY 0.617021 (-6980 3150);
PAINT SKYBLUE (-6980 3150);
FORCEPROP 1 LASTPIN (-7025 3225) $PN 1
J 0
(-7020 3187);
DISPLAY 0.617021 (-7020 3187);
PAINT ORANGE (-7020 3187);
FORCEPROP 1 LAST WATTAGE 1/16W
J 0
(-6985 3100);
DISPLAY 0.617021 (-6985 3100);
PAINT SKYBLUE (-6985 3100);
FORCEPROP 1 LAST VALUE 10.0K
J 0
(-6980 3200);
DISPLAY 0.617021 (-6980 3200);
PAINT SKYBLUE (-6980 3200);
FORCEPROP 1 LAST LOCATION R9E2
J 0
(-6980 3250);
DISPLAY 0.617021 (-6980 3250);
PAINT AQUA (-6980 3250);
FORCEPROP 2 LAST CDS_LIB mstr_discrete
J 0
(-7025 3125);
PAINT ORANGE (-7025 3125);
DISPLAY INVISIBLE (-7025 3125);
FORCEPROP 2 LAST CDS_LOCATION R9E2
J 0
(-6980 3250);
DISPLAY 0.617021 (-6980 3250);
PAINT AQUA (-6980 3250);
DISPLAY INVISIBLE (-6980 3250);
FORCEPROP 2 LAST ROOM NIC_SPRV
J 0
(-6975 3300);
DISPLAY 1.021277 (-6975 3300);
PAINT ORANGE (-6975 3300);
DISPLAY INVISIBLE (-6975 3300);
FORCEPROP 1 LAST PATH I177
J 0
(-6975 3300);
DISPLAY 0.978723 (-6975 3300);
PAINT WHITE (-6975 3300);
DISPLAY INVISIBLE (-6975 3300);
FORCEPROP 2 LAST SEC 1
J 0
(-6975 3350);
DISPLAY 0.680851 (-6975 3350);
PAINT MONO (-6975 3350);
DISPLAY INVISIBLE (-6975 3350);
FORCEPROP 2 LAST SEC_TYPE 0402
J 0
(-6975 3350);
DISPLAY 1.021277 (-6975 3350);
PAINT ORANGE (-6975 3350);
DISPLAY INVISIBLE (-6975 3350);
FORCEPROP 2 LAST BOM_COST NT_GBE_BASE
J 0
(-6975 3350);
DISPLAY 1.021277 (-6975 3350);
PAINT ORANGE (-6975 3350);
DISPLAY INVISIBLE (-6975 3350);
FORCEADD RES..2
(-7275 3125);
FORCEPROP 1 LASTPIN (-7275 3025) $PN 2
J 0
(-7270 3035);
DISPLAY 0.617021 (-7270 3035);
PAINT ORANGE (-7270 3035);
FORCEPROP 1 LAST TOLERANCE 1%
J 0
(-7230 3150);
DISPLAY 0.617021 (-7230 3150);
PAINT SKYBLUE (-7230 3150);
FORCEPROP 1 LASTPIN (-7275 3225) $PN 1
J 0
(-7270 3187);
DISPLAY 0.617021 (-7270 3187);
PAINT ORANGE (-7270 3187);
FORCEPROP 1 LAST WATTAGE 1/16W
J 0
(-7235 3100);
DISPLAY 0.617021 (-7235 3100);
PAINT SKYBLUE (-7235 3100);
FORCEPROP 1 LAST MATERIAL CHIP
J 0
(-7235 3050);
DISPLAY 0.617021 (-7235 3050);
PAINT SKYBLUE (-7235 3050);
FORCEPROP 1 LAST PACK_TYPE 0402
J 0
(-7235 2950);
DISPLAY 0.617021 (-7235 2950);
PAINT SKYBLUE (-7235 2950);
FORCEPROP 1 LAST VALUE 10.0K
J 0
(-7230 3200);
DISPLAY 0.617021 (-7230 3200);
PAINT SKYBLUE (-7230 3200);
FORCEPROP 1 LAST PART_NUMBER G21796-016
J 0
(-7235 3000);
DISPLAY 0.617021 (-7235 3000);
PAINT BLUE (-7235 3000);
FORCEPROP 1 LAST LOCATION R9E3
J 0
(-7230 3250);
DISPLAY 0.617021 (-7230 3250);
PAINT AQUA (-7230 3250);
FORCEPROP 2 LAST CDS_LIB mstr_discrete
J 0
(-7275 3125);
PAINT ORANGE (-7275 3125);
DISPLAY INVISIBLE (-7275 3125);
FORCEPROP 2 LAST CDS_LOCATION R9E3
J 0
(-7230 3250);
DISPLAY 0.617021 (-7230 3250);
PAINT AQUA (-7230 3250);
DISPLAY INVISIBLE (-7230 3250);
FORCEPROP 2 LAST ROOM NIC_SPRV
J 0
(-7225 3300);
DISPLAY 1.021277 (-7225 3300);
PAINT ORANGE (-7225 3300);
DISPLAY INVISIBLE (-7225 3300);
FORCEPROP 1 LAST PATH I178
J 0
(-7225 3300);
DISPLAY 0.978723 (-7225 3300);
PAINT WHITE (-7225 3300);
DISPLAY INVISIBLE (-7225 3300);
FORCEPROP 2 LAST SEC 1
J 0
(-7225 3350);
DISPLAY 0.680851 (-7225 3350);
PAINT MONO (-7225 3350);
DISPLAY INVISIBLE (-7225 3350);
FORCEPROP 2 LAST SEC_TYPE 0402
J 0
(-7225 3350);
DISPLAY 1.021277 (-7225 3350);
PAINT ORANGE (-7225 3350);
DISPLAY INVISIBLE (-7225 3350);
FORCEPROP 2 LAST BOM_COST NT_GBE_BASE
J 0
(-7225 3350);
DISPLAY 1.021277 (-7225 3350);
PAINT ORANGE (-7225 3350);
DISPLAY INVISIBLE (-7225 3350);
FORCEADD RES..2
(-7525 3125);
FORCEPROP 1 LASTPIN (-7525 3025) $PN 2
J 0
(-7520 3035);
DISPLAY 0.617021 (-7520 3035);
PAINT ORANGE (-7520 3035);
FORCEPROP 1 LAST PACK_TYPE 0402
J 0
(-7485 2950);
DISPLAY 0.617021 (-7485 2950);
PAINT SKYBLUE (-7485 2950);
FORCEPROP 1 LAST PART_NUMBER G21796-016
J 0
(-7485 3000);
DISPLAY 0.617021 (-7485 3000);
PAINT BLUE (-7485 3000);
FORCEPROP 1 LAST MATERIAL CHIP
J 0
(-7485 3050);
DISPLAY 0.617021 (-7485 3050);
PAINT SKYBLUE (-7485 3050);
FORCEPROP 1 LASTPIN (-7525 3225) $PN 1
J 0
(-7520 3187);
DISPLAY 0.617021 (-7520 3187);
PAINT ORANGE (-7520 3187);
FORCEPROP 1 LAST WATTAGE 1/16W
J 0
(-7485 3100);
DISPLAY 0.617021 (-7485 3100);
PAINT SKYBLUE (-7485 3100);
FORCEPROP 1 LAST TOLERANCE 1%
J 0
(-7480 3150);
DISPLAY 0.617021 (-7480 3150);
PAINT SKYBLUE (-7480 3150);
FORCEPROP 1 LAST VALUE 10.0K
J 0
(-7480 3200);
DISPLAY 0.617021 (-7480 3200);
PAINT SKYBLUE (-7480 3200);
FORCEPROP 1 LAST LOCATION R9E1
J 0
(-7480 3250);
DISPLAY 0.617021 (-7480 3250);
PAINT AQUA (-7480 3250);
FORCEPROP 2 LAST CDS_LIB mstr_discrete
J 0
(-7525 3125);
PAINT ORANGE (-7525 3125);
DISPLAY INVISIBLE (-7525 3125);
FORCEPROP 2 LAST CDS_LOCATION R9E1
J 0
(-7480 3250);
DISPLAY 0.617021 (-7480 3250);
PAINT AQUA (-7480 3250);
DISPLAY INVISIBLE (-7480 3250);
FORCEPROP 2 LAST ROOM NIC_SPRV
J 0
(-7475 3300);
DISPLAY 1.021277 (-7475 3300);
PAINT ORANGE (-7475 3300);
DISPLAY INVISIBLE (-7475 3300);
FORCEPROP 1 LAST PATH I179
J 0
(-7475 3300);
DISPLAY 0.978723 (-7475 3300);
PAINT WHITE (-7475 3300);
DISPLAY INVISIBLE (-7475 3300);
FORCEPROP 2 LAST SEC 1
J 0
(-7475 3350);
DISPLAY 0.680851 (-7475 3350);
PAINT MONO (-7475 3350);
DISPLAY INVISIBLE (-7475 3350);
FORCEPROP 2 LAST BOM_COST NT_GBE_BASE
J 0
(-7475 3350);
DISPLAY 1.021277 (-7475 3350);
PAINT ORANGE (-7475 3350);
DISPLAY INVISIBLE (-7475 3350);
FORCEPROP 2 LAST SEC_TYPE 0402
J 0
(-7475 3350);
DISPLAY 1.021277 (-7475 3350);
PAINT ORANGE (-7475 3350);
DISPLAY INVISIBLE (-7475 3350);
FORCEADD P3V3_STBY..1
(-7525 3450);
FORCEPROP 3 LASTPIN (-7525 3400) SIG_NAME P3V3_STBY\g
J 0
(-7515 3410);
DISPLAY 0.659574 (-7515 3410);
PAINT MONO (-7515 3410);
DISPLAY INVISIBLE (-7515 3410);
FORCEPROP 1 LAST HDL_POWER P3V3_STBY
J 0
(-7825 3325);
DISPLAY 0.872340 (-7825 3325);
PAINT ORANGE (-7825 3325);
DISPLAY INVISIBLE (-7825 3325);
FORCEPROP 1 LAST PATH I180
J 0
(-7480 3452);
DISPLAY 0.340426 (-7480 3452);
PAINT GREEN (-7480 3452);
DISPLAY INVISIBLE (-7480 3452);
FORCEPROP 1 LAST BODY_TYPE PLUMBING
J 0
(-7570 3407);
DISPLAY 0.340426 (-7570 3407);
PAINT GREEN (-7570 3407);
DISPLAY INVISIBLE (-7570 3407);
FORCEPROP 2 LAST CDS_LIB mstr_symbols
J 0
(-7525 3450);
PAINT ORANGE (-7525 3450);
DISPLAY INVISIBLE (-7525 3450);
FORCEPROP 1 LAST SIZE 1B
J 0
(-7480 3472);
DISPLAY 0.340426 (-7480 3472);
PAINT GREEN (-7480 3472);
DISPLAY INVISIBLE (-7480 3472);
FORCEPROP 1 LAST VOLTAGE 3.3V
J 0
(-7570 3407);
DISPLAY 0.340426 (-7570 3407);
PAINT SKYBLUE (-7570 3407);
DISPLAY INVISIBLE (-7570 3407);
FORCEADD RES..1
(-1500 2825);
FORCEPROP 1 LAST WATTAGE 1/16W
J 2
(-1800 2775);
DISPLAY 0.617021 (-1800 2775);
PAINT SKYBLUE (-1800 2775);
FORCEPROP 1 LAST PART_NUMBER G21796-016
J 0
(-1850 2825);
DISPLAY 0.617021 (-1850 2825);
PAINT BLUE (-1850 2825);
FORCEPROP 1 LASTPIN (-1600 2825) $PN 1
J 0
(-1588 2837);
DISPLAY 0.617021 (-1588 2837);
PAINT ORANGE (-1588 2837);
FORCEPROP 1 LAST TOLERANCE 1%
J 0
(-1600 2775);
DISPLAY 0.617021 (-1600 2775);
PAINT SKYBLUE (-1600 2775);
FORCEPROP 1 LAST VALUE 10.0K
J 2
(-1625 2775);
DISPLAY 0.617021 (-1625 2775);
PAINT SKYBLUE (-1625 2775);
FORCEPROP 1 LAST MATERIAL CHIP
J 0
(-1450 2775);
DISPLAY 0.617021 (-1450 2775);
PAINT SKYBLUE (-1450 2775);
FORCEPROP 1 LASTPIN (-1400 2825) $PN 2
J 0
(-1438 2837);
DISPLAY 0.617021 (-1438 2837);
PAINT ORANGE (-1438 2837);
FORCEPROP 1 LAST LOCATION R9E22
J 0
(-1350 2825);
DISPLAY 0.617021 (-1350 2825);
PAINT AQUA (-1350 2825);
FORCEPROP 1 LAST PACK_TYPE 0402
J 0
(-1300 2775);
DISPLAY 0.617021 (-1300 2775);
PAINT SKYBLUE (-1300 2775);
FORCEPROP 2 LAST ROOM NIC_SPRV
J 0
(-1550 2925);
DISPLAY 1.021277 (-1550 2925);
PAINT ORANGE (-1550 2925);
DISPLAY INVISIBLE (-1550 2925);
FORCEPROP 1 LAST PATH I181
J 0
(-1550 2975);
DISPLAY 0.978723 (-1550 2975);
PAINT WHITE (-1550 2975);
DISPLAY INVISIBLE (-1550 2975);
FORCEPROP 2 LAST SEC 1
J 0
(-1550 3025);
DISPLAY 0.680851 (-1550 3025);
PAINT MONO (-1550 3025);
DISPLAY INVISIBLE (-1550 3025);
FORCEPROP 2 LAST BOM_COST NT_GBE_BASE
J 0
(-1550 2975);
DISPLAY 1.021277 (-1550 2975);
PAINT ORANGE (-1550 2975);
DISPLAY INVISIBLE (-1550 2975);
FORCEPROP 2 LAST SEC_TYPE 0402
J 0
(-1550 3025);
DISPLAY 1.021277 (-1550 3025);
PAINT ORANGE (-1550 3025);
DISPLAY INVISIBLE (-1550 3025);
FORCEPROP 2 LAST CDS_LIB mstr_discrete
J 0
(-1500 2825);
PAINT ORANGE (-1500 2825);
DISPLAY INVISIBLE (-1500 2825);
FORCEPROP 2 LAST CDS_LOCATION R9E22
J 0
(-1350 2825);
DISPLAY 0.617021 (-1350 2825);
PAINT AQUA (-1350 2825);
DISPLAY INVISIBLE (-1350 2825);
FORCEADD P3V3_STBY..1
(-1175 3200);
FORCEPROP 3 LASTPIN (-1175 3150) SIG_NAME P3V3_STBY\g
J 0
(-1165 3160);
DISPLAY 0.659574 (-1165 3160);
PAINT MONO (-1165 3160);
DISPLAY INVISIBLE (-1165 3160);
FORCEPROP 1 LAST HDL_POWER P3V3_STBY
J 0
(-1475 3075);
DISPLAY 0.872340 (-1475 3075);
PAINT ORANGE (-1475 3075);
DISPLAY INVISIBLE (-1475 3075);
FORCEPROP 1 LAST PATH I182
J 0
(-1130 3202);
DISPLAY 0.340426 (-1130 3202);
PAINT GREEN (-1130 3202);
DISPLAY INVISIBLE (-1130 3202);
FORCEPROP 1 LAST BODY_TYPE PLUMBING
J 0
(-1220 3157);
DISPLAY 0.340426 (-1220 3157);
PAINT GREEN (-1220 3157);
DISPLAY INVISIBLE (-1220 3157);
FORCEPROP 2 LAST CDS_LIB mstr_symbols
J 0
(-1175 3200);
PAINT ORANGE (-1175 3200);
DISPLAY INVISIBLE (-1175 3200);
FORCEPROP 1 LAST SIZE 1B
J 0
(-1130 3222);
DISPLAY 0.340426 (-1130 3222);
PAINT GREEN (-1130 3222);
DISPLAY INVISIBLE (-1130 3222);
FORCEPROP 1 LAST VOLTAGE 3.3V
J 0
(-1220 3157);
DISPLAY 0.340426 (-1220 3157);
PAINT SKYBLUE (-1220 3157);
DISPLAY INVISIBLE (-1220 3157);
FORCEADD OFFPAGE..2
(-2600 3825);
FORCEPROP 2 LAST $XR0 141 
J 0
(-2411 3825);
DISPLAY 0.638298 (-2411 3825);
PAINT MONO (-2411 3825);
FORCEPROP 1 LAST COMMENT_BODY TRUE
J 0
(-2645 3730);
DISPLAY 0.872340 (-2645 3730);
PAINT GREEN (-2645 3730);
DISPLAY INVISIBLE (-2645 3730);
FORCEPROP 2 LAST CDS_LIB mstr_standard
J 0
(-2600 3825);
PAINT ORANGE (-2600 3825);
DISPLAY INVISIBLE (-2600 3825);
FORCEPROP 2 LAST PATH I183
J 0
(-2550 3900);
DISPLAY 1.021277 (-2550 3900);
PAINT ORANGE (-2550 3900);
DISPLAY INVISIBLE (-2550 3900);
FORCEPROP 1 LAST OFFPAGE TRUE
J 0
(-2275 3700);
DISPLAY 0.872340 (-2275 3700);
PAINT GREEN (-2275 3700);
DISPLAY INVISIBLE (-2275 3700);
FORCEADD OFFPAGE..2
(-2600 3775);
FORCEPROP 2 LAST $XR0 141 
J 0
(-2411 3775);
DISPLAY 0.638298 (-2411 3775);
PAINT MONO (-2411 3775);
FORCEPROP 1 LAST COMMENT_BODY TRUE
J 0
(-2645 3680);
DISPLAY 0.872340 (-2645 3680);
PAINT GREEN (-2645 3680);
DISPLAY INVISIBLE (-2645 3680);
FORCEPROP 2 LAST CDS_LIB mstr_standard
J 0
(-2600 3775);
PAINT ORANGE (-2600 3775);
DISPLAY INVISIBLE (-2600 3775);
FORCEPROP 2 LAST PATH I184
J 0
(-2425 3850);
DISPLAY 1.021277 (-2425 3850);
PAINT ORANGE (-2425 3850);
DISPLAY INVISIBLE (-2425 3850);
FORCEPROP 1 LAST OFFPAGE TRUE
J 0
(-2275 3650);
DISPLAY 0.872340 (-2275 3650);
PAINT GREEN (-2275 3650);
DISPLAY INVISIBLE (-2275 3650);
FORCEADD OFFPAGE..2
(-2600 3725);
FORCEPROP 2 LAST $XR0 141 
J 0
(-2411 3725);
DISPLAY 0.638298 (-2411 3725);
PAINT MONO (-2411 3725);
FORCEPROP 1 LAST COMMENT_BODY TRUE
J 0
(-2645 3630);
DISPLAY 0.872340 (-2645 3630);
PAINT GREEN (-2645 3630);
DISPLAY INVISIBLE (-2645 3630);
FORCEPROP 2 LAST CDS_LIB mstr_standard
J 0
(-2600 3725);
PAINT ORANGE (-2600 3725);
DISPLAY INVISIBLE (-2600 3725);
FORCEPROP 2 LAST PATH I185
J 0
(-2425 3800);
DISPLAY 1.021277 (-2425 3800);
PAINT ORANGE (-2425 3800);
DISPLAY INVISIBLE (-2425 3800);
FORCEPROP 1 LAST OFFPAGE TRUE
J 0
(-2275 3600);
DISPLAY 0.872340 (-2275 3600);
PAINT GREEN (-2275 3600);
DISPLAY INVISIBLE (-2275 3600);
FORCEADD P3V3_STBY..1
(-6725 4000);
FORCEPROP 3 LASTPIN (-6725 3950) SIG_NAME P3V3_STBY\g
J 0
(-6715 3960);
DISPLAY 0.659574 (-6715 3960);
PAINT MONO (-6715 3960);
DISPLAY INVISIBLE (-6715 3960);
FORCEPROP 1 LAST HDL_POWER P3V3_STBY
J 0
(-7025 3875);
DISPLAY 0.872340 (-7025 3875);
PAINT ORANGE (-7025 3875);
DISPLAY INVISIBLE (-7025 3875);
FORCEPROP 1 LAST BODY_TYPE PLUMBING
J 0
(-6770 3957);
DISPLAY 0.340426 (-6770 3957);
PAINT GREEN (-6770 3957);
DISPLAY INVISIBLE (-6770 3957);
FORCEPROP 1 LAST VOLTAGE 3.3V
J 0
(-6770 3957);
DISPLAY 0.340426 (-6770 3957);
PAINT SKYBLUE (-6770 3957);
DISPLAY INVISIBLE (-6770 3957);
FORCEPROP 1 LAST PATH I186
J 0
(-6680 4002);
DISPLAY 0.340426 (-6680 4002);
PAINT GREEN (-6680 4002);
DISPLAY INVISIBLE (-6680 4002);
FORCEPROP 1 LAST SIZE 1B
J 0
(-6680 4022);
DISPLAY 0.340426 (-6680 4022);
PAINT GREEN (-6680 4022);
DISPLAY INVISIBLE (-6680 4022);
FORCEPROP 2 LAST CDS_LIB mstr_symbols
J 0
(-6725 4000);
PAINT ORANGE (-6725 4000);
DISPLAY INVISIBLE (-6725 4000);
FORCEADD P3V3_STBY..1
(-900 4050);
FORCEPROP 3 LASTPIN (-900 4000) SIG_NAME P3V3_STBY\g
J 0
(-890 4010);
DISPLAY 0.659574 (-890 4010);
PAINT MONO (-890 4010);
DISPLAY INVISIBLE (-890 4010);
FORCEPROP 1 LAST HDL_POWER P3V3_STBY
J 0
(-1200 3925);
DISPLAY 0.872340 (-1200 3925);
PAINT ORANGE (-1200 3925);
DISPLAY INVISIBLE (-1200 3925);
FORCEPROP 1 LAST VOLTAGE 3.3V
J 0
(-945 4007);
DISPLAY 0.340426 (-945 4007);
PAINT SKYBLUE (-945 4007);
DISPLAY INVISIBLE (-945 4007);
FORCEPROP 2 LAST CDS_LIB mstr_symbols
J 0
(-900 4050);
PAINT ORANGE (-900 4050);
DISPLAY INVISIBLE (-900 4050);
FORCEPROP 1 LAST BODY_TYPE PLUMBING
J 0
(-945 4007);
DISPLAY 0.340426 (-945 4007);
PAINT GREEN (-945 4007);
DISPLAY INVISIBLE (-945 4007);
FORCEPROP 1 LAST SIZE 1B
J 0
(-855 4072);
DISPLAY 0.340426 (-855 4072);
PAINT GREEN (-855 4072);
DISPLAY INVISIBLE (-855 4072);
FORCEPROP 1 LAST PATH I188
J 0
(-855 4052);
DISPLAY 0.340426 (-855 4052);
PAINT GREEN (-855 4052);
DISPLAY INVISIBLE (-855 4052);
FORCEADD P3V3_STBY..1
(-5275 1175);
FORCEPROP 3 LASTPIN (-5275 1125) SIG_NAME P3V3_STBY\g
J 0
(-5265 1135);
DISPLAY 0.659574 (-5265 1135);
PAINT MONO (-5265 1135);
DISPLAY INVISIBLE (-5265 1135);
FORCEPROP 1 LAST HDL_POWER P3V3_STBY
J 0
(-5575 1050);
DISPLAY 0.872340 (-5575 1050);
PAINT ORANGE (-5575 1050);
DISPLAY INVISIBLE (-5575 1050);
FORCEPROP 1 LAST BODY_TYPE PLUMBING
J 0
(-5320 1132);
DISPLAY 0.340426 (-5320 1132);
PAINT GREEN (-5320 1132);
DISPLAY INVISIBLE (-5320 1132);
FORCEPROP 2 LAST CDS_LIB mstr_symbols
J 0
(-5275 1175);
PAINT ORANGE (-5275 1175);
DISPLAY INVISIBLE (-5275 1175);
FORCEPROP 1 LAST VOLTAGE 3.3V
J 0
(-5320 1132);
DISPLAY 0.340426 (-5320 1132);
PAINT SKYBLUE (-5320 1132);
DISPLAY INVISIBLE (-5320 1132);
FORCEPROP 1 LAST PATH I189
J 0
(-5230 1177);
DISPLAY 0.340426 (-5230 1177);
PAINT GREEN (-5230 1177);
DISPLAY INVISIBLE (-5230 1177);
FORCEPROP 1 LAST SIZE 1B
J 0
(-5230 1197);
DISPLAY 0.340426 (-5230 1197);
PAINT GREEN (-5230 1197);
DISPLAY INVISIBLE (-5230 1197);
FORCEADD OFFPAGE..5
(-6750 2225);
FORCEPROP 2 LAST $XR0 142 
J 0
(-7035 2225);
DISPLAY 0.638298 (-7035 2225);
PAINT MONO (-7035 2225);
FORCEPROP 2 LAST CDS_LIB mstr_standard
J 0
(-6750 2225);
PAINT ORANGE (-6750 2225);
DISPLAY INVISIBLE (-6750 2225);
FORCEPROP 2 LAST PATH I191
J 0
(-6700 2300);
DISPLAY 1.021277 (-6700 2300);
PAINT ORANGE (-6700 2300);
DISPLAY INVISIBLE (-6700 2300);
FORCEPROP 1 LAST OFFPAGE TRUE
J 0
(-6425 2100);
DISPLAY 0.872340 (-6425 2100);
PAINT GREEN (-6425 2100);
DISPLAY INVISIBLE (-6425 2100);
FORCEPROP 1 LAST COMMENT_BODY TRUE
J 0
(-6650 2150);
DISPLAY 0.872340 (-6650 2150);
PAINT GREEN (-6650 2150);
DISPLAY INVISIBLE (-6650 2150);
FORCEADD OFFPAGE..2
(-425 4250);
FORCEPROP 2 LAST $XR0 139 
J 0
(-236 4250);
DISPLAY 0.638298 (-236 4250);
PAINT MONO (-236 4250);
FORCEPROP 2 LAST $XR1 119 
J 0
(-116 4250);
DISPLAY 0.638298 (-116 4250);
PAINT MONO (-116 4250);
FORCEPROP 2 LAST $XR2 146 
J 0
(-236 4214);
DISPLAY 0.638298 (-236 4214);
PAINT MONO (-236 4214);
FORCEPROP 2 LAST CDS_LIB mstr_standard
J 0
(-425 4250);
PAINT ORANGE (-425 4250);
DISPLAY INVISIBLE (-425 4250);
FORCEPROP 1 LAST COMMENT_BODY TRUE
J 0
(-470 4155);
DISPLAY 0.872340 (-470 4155);
PAINT GREEN (-470 4155);
DISPLAY INVISIBLE (-470 4155);
FORCEPROP 1 LAST OFFPAGE TRUE
J 0
(-100 4125);
DISPLAY 0.872340 (-100 4125);
PAINT GREEN (-100 4125);
DISPLAY INVISIBLE (-100 4125);
FORCEPROP 2 LAST PATH I192
J 0
(-225 4300);
DISPLAY 1.021277 (-225 4300);
PAINT ORANGE (-225 4300);
DISPLAY INVISIBLE (-225 4300);
FORCEADD RES..2
(-1000 4475);
FORCEPROP 1 LAST PACK_TYPE 0402
J 0
(-960 4300);
DISPLAY 0.617021 (-960 4300);
PAINT SKYBLUE (-960 4300);
FORCEPROP 1 LASTPIN (-1000 4375) $PN 2
J 0
(-995 4385);
DISPLAY 0.617021 (-995 4385);
PAINT ORANGE (-995 4385);
FORCEPROP 1 LAST TOLERANCE 1%
J 0
(-955 4500);
DISPLAY 0.617021 (-955 4500);
PAINT SKYBLUE (-955 4500);
FORCEPROP 1 LASTPIN (-1000 4575) $PN 1
J 0
(-995 4537);
DISPLAY 0.617021 (-995 4537);
PAINT ORANGE (-995 4537);
FORCEPROP 1 LAST WATTAGE 1/16W
J 0
(-960 4450);
DISPLAY 0.617021 (-960 4450);
PAINT SKYBLUE (-960 4450);
FORCEPROP 1 LAST VALUE 3.32K
J 0
(-955 4550);
DISPLAY 0.617021 (-955 4550);
PAINT SKYBLUE (-955 4550);
FORCEPROP 1 LAST MATERIAL CHIP
J 0
(-960 4400);
DISPLAY 0.617021 (-960 4400);
PAINT SKYBLUE (-960 4400);
FORCEPROP 1 LAST PART_NUMBER G21796-027
J 0
(-960 4350);
DISPLAY 0.617021 (-960 4350);
PAINT BLUE (-960 4350);
FORCEPROP 1 LAST LOCATION R9E7
J 0
(-955 4600);
DISPLAY 0.617021 (-955 4600);
PAINT AQUA (-955 4600);
FORCEPROP 2 LAST CDS_LIB mstr_discrete
J 0
(-1000 4475);
PAINT ORANGE (-1000 4475);
DISPLAY INVISIBLE (-1000 4475);
FORCEPROP 2 LAST CDS_LOCATION R9E7
J 0
(-955 4600);
DISPLAY 0.617021 (-955 4600);
PAINT AQUA (-955 4600);
DISPLAY INVISIBLE (-955 4600);
FORCEPROP 2 LAST ROOM NIC_SPRV
J 0
(-950 4650);
DISPLAY 1.021277 (-950 4650);
PAINT ORANGE (-950 4650);
DISPLAY INVISIBLE (-950 4650);
FORCEPROP 1 LAST PATH I193
J 0
(-950 4650);
DISPLAY 0.978723 (-950 4650);
PAINT WHITE (-950 4650);
DISPLAY INVISIBLE (-950 4650);
FORCEPROP 2 LAST $SEC 1
J 0
(-950 4700);
PAINT MONO (-950 4700);
DISPLAY INVISIBLE (-950 4700);
FORCEPROP 2 LAST CDS_SEC 1
J 0
(-950 4700);
PAINT MONO (-950 4700);
DISPLAY INVISIBLE (-950 4700);
FORCEPROP 2 LAST BOM_COST NT_GBE_BASE
J 0
(-950 4700);
DISPLAY 1.021277 (-950 4700);
PAINT ORANGE (-950 4700);
DISPLAY INVISIBLE (-950 4700);
FORCEADD P3V3_STBY..1
(-1000 4700);
FORCEPROP 3 LASTPIN (-1000 4650) SIG_NAME P3V3_STBY\g
J 0
(-990 4660);
DISPLAY 0.659574 (-990 4660);
PAINT MONO (-990 4660);
DISPLAY INVISIBLE (-990 4660);
FORCEPROP 1 LAST HDL_POWER P3V3_STBY
J 0
(-1300 4575);
DISPLAY 0.872340 (-1300 4575);
PAINT ORANGE (-1300 4575);
DISPLAY INVISIBLE (-1300 4575);
FORCEPROP 1 LAST BODY_TYPE PLUMBING
J 0
(-1045 4657);
DISPLAY 0.340426 (-1045 4657);
PAINT GREEN (-1045 4657);
DISPLAY INVISIBLE (-1045 4657);
FORCEPROP 1 LAST VOLTAGE 3.3V
J 0
(-1045 4657);
DISPLAY 0.340426 (-1045 4657);
PAINT SKYBLUE (-1045 4657);
DISPLAY INVISIBLE (-1045 4657);
FORCEPROP 1 LAST PATH I194
J 0
(-955 4702);
DISPLAY 0.340426 (-955 4702);
PAINT GREEN (-955 4702);
DISPLAY INVISIBLE (-955 4702);
FORCEPROP 2 LAST CDS_LIB mstr_symbols
J 0
(-1000 4700);
PAINT ORANGE (-1000 4700);
DISPLAY INVISIBLE (-1000 4700);
FORCEPROP 1 LAST SIZE 1B
J 0
(-955 4722);
DISPLAY 0.340426 (-955 4722);
PAINT GREEN (-955 4722);
DISPLAY INVISIBLE (-955 4722);
FORCEADD RES..1
(-6600 550);
FORCEPROP 1 LAST MATERIAL CHIP
J 0
(-6825 500);
DISPLAY 0.617021 (-6825 500);
PAINT SKYBLUE (-6825 500);
FORCEPROP 1 LASTPIN (-6700 550) $PN 1
J 0
(-6688 562);
DISPLAY 0.617021 (-6688 562);
PAINT ORANGE (-6688 562);
FORCEPROP 1 LAST TOLERANCE 5%
J 0
(-6425 500);
DISPLAY 0.617021 (-6425 500);
PAINT SKYBLUE (-6425 500);
FORCEPROP 1 LAST VALUE 0.0
J 2
(-6450 500);
DISPLAY 0.617021 (-6450 500);
PAINT SKYBLUE (-6450 500);
FORCEPROP 1 LAST LOCATION R1R1
J 0
(-6650 600);
DISPLAY 0.617021 (-6650 600);
PAINT AQUA (-6650 600);
FORCEPROP 1 LASTPIN (-6500 550) $PN 2
J 0
(-6538 562);
DISPLAY 0.617021 (-6538 562);
PAINT ORANGE (-6538 562);
FORCEPROP 1 LAST WATTAGE 1/16W
J 2
(-6625 400);
DISPLAY 0.978723 (-6625 400);
PAINT SKYBLUE (-6625 400);
DISPLAY INVISIBLE (-6625 400);
FORCEPROP 1 LAST PACK_TYPE 0402
J 0
(-6350 400);
DISPLAY 0.978723 (-6350 400);
PAINT SKYBLUE (-6350 400);
DISPLAY INVISIBLE (-6350 400);
FORCEPROP 1 LAST PART_NUMBER G21497-005
J 0
(-6650 650);
DISPLAY 0.978723 (-6650 650);
PAINT BLUE (-6650 650);
DISPLAY INVISIBLE (-6650 650);
FORCEPROP 2 LAST ROOM NIC_SPRV
J 0
(-6650 650);
DISPLAY 1.021277 (-6650 650);
PAINT ORANGE (-6650 650);
DISPLAY INVISIBLE (-6650 650);
FORCEPROP 2 LAST BOM_COST NT_GBE_BASE
J 0
(-6650 700);
DISPLAY 1.021277 (-6650 700);
PAINT ORANGE (-6650 700);
DISPLAY INVISIBLE (-6650 700);
FORCEPROP 2 LAST CDS_LOCATION R1R1
J 0
(-6650 600);
DISPLAY 0.617021 (-6650 600);
PAINT AQUA (-6650 600);
DISPLAY INVISIBLE (-6650 600);
FORCEPROP 2 LAST CDS_LIB mstr_discrete
J 0
(-6600 550);
PAINT ORANGE (-6600 550);
DISPLAY INVISIBLE (-6600 550);
FORCEPROP 1 LAST PATH I195
J 0
(-6650 700);
DISPLAY 0.978723 (-6650 700);
PAINT WHITE (-6650 700);
DISPLAY INVISIBLE (-6650 700);
FORCEPROP 2 LAST SEC_TYPE 0402
J 0
(-6650 750);
DISPLAY 1.021277 (-6650 750);
PAINT ORANGE (-6650 750);
DISPLAY INVISIBLE (-6650 750);
FORCEPROP 2 LAST SEC 1
J 0
(-6650 750);
PAINT MONO (-6650 750);
DISPLAY INVISIBLE (-6650 750);
FORCEADD OFFPAGE..2
(-5800 550);
FORCEPROP 2 LAST $XR0 139 
J 0
(-5611 550);
DISPLAY 0.638298 (-5611 550);
PAINT MONO (-5611 550);
FORCEPROP 1 LAST COMMENT_BODY TRUE
J 0
(-5845 455);
DISPLAY 0.872340 (-5845 455);
PAINT GREEN (-5845 455);
DISPLAY INVISIBLE (-5845 455);
FORCEPROP 2 LAST CDS_LIB mstr_standard
J 0
(-5800 550);
PAINT ORANGE (-5800 550);
DISPLAY INVISIBLE (-5800 550);
FORCEPROP 2 LAST PATH I197
J 0
(-5750 625);
DISPLAY 1.021277 (-5750 625);
PAINT ORANGE (-5750 625);
DISPLAY INVISIBLE (-5750 625);
FORCEPROP 1 LAST OFFPAGE TRUE
J 0
(-5475 425);
DISPLAY 0.872340 (-5475 425);
PAINT GREEN (-5475 425);
DISPLAY INVISIBLE (-5475 425);
FORCEADD OFFPAGE..1
(-7125 550);
FORCEPROP 2 LAST $XR0 119 
J 0
(-7377 550);
DISPLAY 0.638298 (-7377 550);
PAINT MONO (-7377 550);
FORCEPROP 2 LAST $XR1 136 
J 0
(-7497 550);
DISPLAY 0.638298 (-7497 550);
PAINT MONO (-7497 550);
FORCEPROP 2 LAST $XR2 191 
J 0
(-7617 550);
DISPLAY 0.638298 (-7617 550);
PAINT MONO (-7617 550);
FORCEPROP 1 LAST OFFPAGE TRUE
J 0
(-6800 425);
DISPLAY 0.872340 (-6800 425);
PAINT GREEN (-6800 425);
DISPLAY INVISIBLE (-6800 425);
FORCEPROP 1 LAST COMMENT_BODY TRUE
J 0
(-7000 450);
DISPLAY 0.872340 (-7000 450);
PAINT GREEN (-7000 450);
DISPLAY INVISIBLE (-7000 450);
FORCEPROP 2 LAST CDS_LIB mstr_standard
J 0
(-7125 550);
PAINT ORANGE (-7125 550);
DISPLAY INVISIBLE (-7125 550);
FORCEPROP 2 LAST PATH I198
J 0
(-7075 625);
DISPLAY 1.021277 (-7075 625);
PAINT ORANGE (-7075 625);
DISPLAY INVISIBLE (-7075 625);
FORCEADD P3V3_STBY..1
(-6350 1050);
FORCEPROP 3 LASTPIN (-6350 1000) SIG_NAME P3V3_STBY\g
J 0
(-6340 1010);
DISPLAY 0.659574 (-6340 1010);
PAINT MONO (-6340 1010);
DISPLAY INVISIBLE (-6340 1010);
FORCEPROP 1 LAST HDL_POWER P3V3_STBY
J 0
(-6650 925);
DISPLAY 0.872340 (-6650 925);
PAINT ORANGE (-6650 925);
DISPLAY INVISIBLE (-6650 925);
FORCEPROP 1 LAST VOLTAGE 3.3V
J 0
(-6395 1007);
DISPLAY 0.340426 (-6395 1007);
PAINT SKYBLUE (-6395 1007);
DISPLAY INVISIBLE (-6395 1007);
FORCEPROP 1 LAST BODY_TYPE PLUMBING
J 0
(-6395 1007);
DISPLAY 0.340426 (-6395 1007);
PAINT GREEN (-6395 1007);
DISPLAY INVISIBLE (-6395 1007);
FORCEPROP 1 LAST PATH I199
J 0
(-6305 1052);
DISPLAY 0.340426 (-6305 1052);
PAINT GREEN (-6305 1052);
DISPLAY INVISIBLE (-6305 1052);
FORCEPROP 2 LAST CDS_LIB mstr_symbols
J 0
(-6350 1050);
PAINT ORANGE (-6350 1050);
DISPLAY INVISIBLE (-6350 1050);
FORCEPROP 1 LAST SIZE 1B
J 0
(-6305 1072);
DISPLAY 0.340426 (-6305 1072);
PAINT GREEN (-6305 1072);
DISPLAY INVISIBLE (-6305 1072);
FORCEADD RES..2
(-6350 775);
FORCEPROP 1 LASTPIN (-6350 675) $PN 2
J 0
(-6345 685);
DISPLAY 0.617021 (-6345 685);
PAINT ORANGE (-6345 685);
FORCEPROP 1 LAST PACK_TYPE 0402
J 0
(-6310 600);
DISPLAY 0.617021 (-6310 600);
PAINT SKYBLUE (-6310 600);
FORCEPROP 1 LAST MATERIAL CHIP
J 0
(-6310 700);
DISPLAY 0.617021 (-6310 700);
PAINT SKYBLUE (-6310 700);
FORCEPROP 1 LAST WATTAGE 1/16W
J 0
(-6310 750);
DISPLAY 0.617021 (-6310 750);
PAINT SKYBLUE (-6310 750);
FORCEPROP 1 LASTPIN (-6350 875) $PN 1
J 0
(-6345 837);
DISPLAY 0.617021 (-6345 837);
PAINT ORANGE (-6345 837);
FORCEPROP 1 LAST VALUE 10.0K
J 0
(-6305 850);
DISPLAY 0.617021 (-6305 850);
PAINT SKYBLUE (-6305 850);
FORCEPROP 1 LAST LOCATION R9E4
J 0
(-6305 900);
DISPLAY 0.617021 (-6305 900);
PAINT AQUA (-6305 900);
FORCEPROP 1 LAST TOLERANCE 1%
J 0
(-6305 800);
DISPLAY 0.617021 (-6305 800);
PAINT SKYBLUE (-6305 800);
FORCEPROP 1 LAST PART_NUMBER G21796-016
J 0
(-6310 650);
DISPLAY 0.617021 (-6310 650);
PAINT BLUE (-6310 650);
FORCEPROP 2 LAST CDS_LIB mstr_discrete
J 0
(-6350 775);
PAINT ORANGE (-6350 775);
DISPLAY INVISIBLE (-6350 775);
FORCEPROP 2 LAST CDS_LOCATION R9E4
J 0
(-6305 900);
DISPLAY 0.617021 (-6305 900);
PAINT AQUA (-6305 900);
DISPLAY INVISIBLE (-6305 900);
FORCEPROP 1 LAST PATH I200
J 0
(-6300 950);
DISPLAY 0.978723 (-6300 950);
PAINT WHITE (-6300 950);
DISPLAY INVISIBLE (-6300 950);
FORCEPROP 2 LAST ROOM NIC_SPRV
J 0
(-6300 950);
DISPLAY 1.021277 (-6300 950);
PAINT ORANGE (-6300 950);
DISPLAY INVISIBLE (-6300 950);
FORCEPROP 2 LAST SEC 1
J 0
(-6300 1000);
PAINT MONO (-6300 1000);
DISPLAY INVISIBLE (-6300 1000);
FORCEPROP 2 LAST SEC_TYPE 0402
J 0
(-6300 1000);
DISPLAY 1.021277 (-6300 1000);
PAINT ORANGE (-6300 1000);
DISPLAY INVISIBLE (-6300 1000);
FORCEPROP 2 LAST BOM_COST NT_GBE_BASE
J 0
(-6300 1000);
DISPLAY 1.021277 (-6300 1000);
PAINT ORANGE (-6300 1000);
DISPLAY INVISIBLE (-6300 1000);
FORCEADD RES..1
(-6875 1575);
FORCEPROP 1 LAST MATERIAL CHIP
J 0
(-7100 1525);
DISPLAY 0.617021 (-7100 1525);
PAINT SKYBLUE (-7100 1525);
FORCEPROP 1 LAST VALUE 0.0
J 2
(-6725 1525);
DISPLAY 0.617021 (-6725 1525);
PAINT SKYBLUE (-6725 1525);
FORCEPROP 1 LASTPIN (-6975 1575) $PN 1
J 0
(-6963 1587);
DISPLAY 0.617021 (-6963 1587);
PAINT ORANGE (-6963 1587);
FORCEPROP 1 LAST LOCATION R9E18
J 0
(-6925 1625);
DISPLAY 0.617021 (-6925 1625);
PAINT AQUA (-6925 1625);
FORCEPROP 1 LASTPIN (-6775 1575) $PN 2
J 0
(-6813 1587);
DISPLAY 0.617021 (-6813 1587);
PAINT ORANGE (-6813 1587);
FORCEPROP 1 LAST TOLERANCE 5%
J 0
(-6700 1525);
DISPLAY 0.617021 (-6700 1525);
PAINT SKYBLUE (-6700 1525);
FORCEPROP 1 LAST WATTAGE 1/16W
J 2
(-6900 1425);
DISPLAY 0.978723 (-6900 1425);
PAINT SKYBLUE (-6900 1425);
DISPLAY INVISIBLE (-6900 1425);
FORCEPROP 1 LAST PART_NUMBER G21497-005
J 0
(-6925 1675);
DISPLAY 0.978723 (-6925 1675);
PAINT BLUE (-6925 1675);
DISPLAY INVISIBLE (-6925 1675);
FORCEPROP 2 LAST BOM_COST NT_GBE_BASE
J 0
(-6925 1725);
DISPLAY 1.021277 (-6925 1725);
PAINT ORANGE (-6925 1725);
DISPLAY INVISIBLE (-6925 1725);
FORCEPROP 2 LAST CDS_LOCATION R9E18
J 0
(-6925 1625);
DISPLAY 0.617021 (-6925 1625);
PAINT AQUA (-6925 1625);
DISPLAY INVISIBLE (-6925 1625);
FORCEPROP 1 LAST PATH I201
J 0
(-6925 1725);
DISPLAY 0.978723 (-6925 1725);
PAINT WHITE (-6925 1725);
DISPLAY INVISIBLE (-6925 1725);
FORCEPROP 2 LAST ROOM NIC_SPRV
J 0
(-6925 1675);
DISPLAY 1.021277 (-6925 1675);
PAINT ORANGE (-6925 1675);
DISPLAY INVISIBLE (-6925 1675);
FORCEPROP 2 LAST SEC_TYPE 0402
J 0
(-6925 1775);
DISPLAY 1.021277 (-6925 1775);
PAINT ORANGE (-6925 1775);
DISPLAY INVISIBLE (-6925 1775);
FORCEPROP 2 LAST SEC 1
J 0
(-6925 1775);
PAINT MONO (-6925 1775);
DISPLAY INVISIBLE (-6925 1775);
FORCEPROP 2 LAST CDS_LIB mstr_discrete
J 0
(-6875 1575);
PAINT ORANGE (-6875 1575);
DISPLAY INVISIBLE (-6875 1575);
FORCEPROP 1 LAST PACK_TYPE 0402
J 0
(-6625 1425);
DISPLAY 0.978723 (-6625 1425);
PAINT SKYBLUE (-6625 1425);
DISPLAY INVISIBLE (-6625 1425);
FORCEADD OFFPAGE..1
(-6750 2275);
FORCEPROP 2 LAST $XR0 139 
J 0
(-7002 2275);
DISPLAY 0.638298 (-7002 2275);
PAINT MONO (-7002 2275);
FORCEPROP 2 LAST CDS_LIB mstr_standard
J 0
(-6750 2275);
PAINT ORANGE (-6750 2275);
DISPLAY INVISIBLE (-6750 2275);
FORCEPROP 2 LAST PATH I202
J 0
(-6700 2350);
DISPLAY 1.021277 (-6700 2350);
PAINT ORANGE (-6700 2350);
DISPLAY INVISIBLE (-6700 2350);
FORCEPROP 1 LAST OFFPAGE TRUE
J 0
(-6425 2150);
DISPLAY 0.872340 (-6425 2150);
PAINT GREEN (-6425 2150);
DISPLAY INVISIBLE (-6425 2150);
FORCEPROP 1 LAST COMMENT_BODY TRUE
J 0
(-6625 2175);
DISPLAY 0.872340 (-6625 2175);
PAINT GREEN (-6625 2175);
DISPLAY INVISIBLE (-6625 2175);
FORCEADD OFFPAGE..2
(-1475 1825);
FORCEPROP 2 LAST $XR0 147 
J 0
(-1286 1825);
DISPLAY 0.638298 (-1286 1825);
PAINT MONO (-1286 1825);
FORCEPROP 2 LAST $XR1 151 
J 0
(-1166 1825);
DISPLAY 0.638298 (-1166 1825);
PAINT MONO (-1166 1825);
FORCEPROP 2 LAST $XR2 121 
J 0
(-1046 1825);
DISPLAY 0.638298 (-1046 1825);
PAINT MONO (-1046 1825);
FORCEPROP 2 LAST $XR3 139 
J 0
(-1046 1825);
DISPLAY 0.638298 (-1046 1825);
PAINT MONO (-1046 1825);
FORCEPROP 1 LAST COMMENT_BODY TRUE
J 0
(-1520 1730);
DISPLAY 0.872340 (-1520 1730);
PAINT GREEN (-1520 1730);
DISPLAY INVISIBLE (-1520 1730);
FORCEPROP 2 LAST CDS_LIB mstr_standard
J 0
(-1475 1825);
PAINT ORANGE (-1475 1825);
DISPLAY INVISIBLE (-1475 1825);
FORCEPROP 1 LAST OFFPAGE TRUE
J 0
(-1150 1700);
DISPLAY 0.872340 (-1150 1700);
PAINT GREEN (-1150 1700);
DISPLAY INVISIBLE (-1150 1700);
FORCEPROP 2 LAST PATH I203
J 0
(-1275 1875);
DISPLAY 1.021277 (-1275 1875);
PAINT ORANGE (-1275 1875);
DISPLAY INVISIBLE (-1275 1875);
FORCEADD GND..1
(-1900 1375);
FORCEPROP 3 LASTPIN (-1900 1425) SIG_NAME GND\g
J 0
(-1890 1435);
DISPLAY 0.659574 (-1890 1435);
PAINT MONO (-1890 1435);
DISPLAY INVISIBLE (-1890 1435);
FORCEPROP 1 LAST PATH I204
J 0
(-1825 1375);
DISPLAY 0.872340 (-1825 1375);
PAINT AQUA (-1825 1375);
DISPLAY INVISIBLE (-1825 1375);
FORCEPROP 1 LAST BODY_TYPE PLUMBING
J 0
(-1945 1332);
DISPLAY 0.340426 (-1945 1332);
PAINT GREEN (-1945 1332);
DISPLAY INVISIBLE (-1945 1332);
FORCEPROP 2 LAST CDS_LIB mstr_symbols
J 0
(-1900 1375);
PAINT ORANGE (-1900 1375);
DISPLAY INVISIBLE (-1900 1375);
FORCEPROP 1 LAST SIZE 1B
J 0
(-1825 1325);
DISPLAY 0.872340 (-1825 1325);
PAINT AQUA (-1825 1325);
DISPLAY INVISIBLE (-1825 1325);
FORCEPROP 1 LAST VOLTAGE 0.0V
J 0
(-1945 1332);
DISPLAY 0.340426 (-1945 1332);
PAINT SKYBLUE (-1945 1332);
DISPLAY INVISIBLE (-1945 1332);
FORCEPROP 1 LAST HDL_POWER GND
J 0
(-1900 1525);
DISPLAY 0.872340 (-1900 1525);
PAINT GREEN (-1900 1525);
DISPLAY INVISIBLE (-1900 1525);
FORCEADD OFFPAGE..2
(-2450 1700);
FORCEPROP 2 LAST $XR0 101 
J 0
(-2261 1700);
DISPLAY 0.638298 (-2261 1700);
PAINT MONO (-2261 1700);
FORCEPROP 2 LAST $XR1 139 
J 0
(-2141 1700);
DISPLAY 0.638298 (-2141 1700);
PAINT MONO (-2141 1700);
FORCEPROP 2 LAST CDS_LIB mstr_standard
J 0
(-2450 1700);
PAINT ORANGE (-2450 1700);
DISPLAY INVISIBLE (-2450 1700);
FORCEPROP 1 LAST COMMENT_BODY TRUE
J 0
(-2495 1605);
DISPLAY 0.872340 (-2495 1605);
PAINT GREEN (-2495 1605);
DISPLAY INVISIBLE (-2495 1605);
FORCEPROP 1 LAST OFFPAGE TRUE
J 0
(-2125 1575);
DISPLAY 0.872340 (-2125 1575);
PAINT GREEN (-2125 1575);
DISPLAY INVISIBLE (-2125 1575);
FORCEPROP 2 LAST PATH I206
J 0
(-2250 1750);
DISPLAY 1.021277 (-2250 1750);
PAINT ORANGE (-2250 1750);
DISPLAY INVISIBLE (-2250 1750);
FORCEADD GND..1
(-2875 1250);
FORCEPROP 3 LASTPIN (-2875 1300) SIG_NAME GND\g
J 0
(-2865 1310);
DISPLAY 0.659574 (-2865 1310);
PAINT MONO (-2865 1310);
DISPLAY INVISIBLE (-2865 1310);
FORCEPROP 1 LAST BODY_TYPE PLUMBING
J 0
(-2920 1207);
DISPLAY 0.340426 (-2920 1207);
PAINT GREEN (-2920 1207);
DISPLAY INVISIBLE (-2920 1207);
FORCEPROP 1 LAST VOLTAGE 0.0V
J 0
(-2920 1207);
DISPLAY 0.340426 (-2920 1207);
PAINT SKYBLUE (-2920 1207);
DISPLAY INVISIBLE (-2920 1207);
FORCEPROP 2 LAST CDS_LIB mstr_symbols
J 0
(-2875 1250);
PAINT ORANGE (-2875 1250);
DISPLAY INVISIBLE (-2875 1250);
FORCEPROP 1 LAST HDL_POWER GND
J 0
(-2875 1400);
DISPLAY 0.872340 (-2875 1400);
PAINT GREEN (-2875 1400);
DISPLAY INVISIBLE (-2875 1400);
FORCEPROP 1 LAST PATH I207
J 0
(-2800 1250);
DISPLAY 0.872340 (-2800 1250);
PAINT AQUA (-2800 1250);
DISPLAY INVISIBLE (-2800 1250);
FORCEPROP 1 LAST SIZE 1B
J 0
(-2800 1200);
DISPLAY 0.872340 (-2800 1200);
PAINT AQUA (-2800 1200);
DISPLAY INVISIBLE (-2800 1200);
FORCEADD OFFPAGE..2
(-450 1725);
FORCEPROP 2 LAST $XR0 121 
J 0
(-261 1725);
DISPLAY 0.638298 (-261 1725);
PAINT MONO (-261 1725);
FORCEPROP 2 LAST $XR1 139 
J 0
(-141 1725);
DISPLAY 0.638298 (-141 1725);
PAINT MONO (-141 1725);
FORCEPROP 2 LAST $XR2 147 
J 0
(-261 1689);
DISPLAY 0.638298 (-261 1689);
PAINT MONO (-261 1689);
FORCEPROP 2 LAST CDS_LIB mstr_standard
J 0
(-450 1725);
PAINT ORANGE (-450 1725);
DISPLAY INVISIBLE (-450 1725);
FORCEPROP 1 LAST COMMENT_BODY TRUE
J 0
(-495 1630);
DISPLAY 0.872340 (-495 1630);
PAINT GREEN (-495 1630);
DISPLAY INVISIBLE (-495 1630);
FORCEPROP 1 LAST OFFPAGE TRUE
J 0
(-125 1600);
DISPLAY 0.872340 (-125 1600);
PAINT GREEN (-125 1600);
DISPLAY INVISIBLE (-125 1600);
FORCEPROP 2 LAST PATH I209
J 0
(-250 1775);
DISPLAY 1.021277 (-250 1775);
PAINT ORANGE (-250 1775);
DISPLAY INVISIBLE (-250 1775);
FORCEADD GND..1
(-875 1275);
FORCEPROP 3 LASTPIN (-875 1325) SIG_NAME GND\g
J 0
(-865 1335);
DISPLAY 0.659574 (-865 1335);
PAINT MONO (-865 1335);
DISPLAY INVISIBLE (-865 1335);
FORCEPROP 1 LAST VOLTAGE 0.0V
J 0
(-920 1232);
DISPLAY 0.340426 (-920 1232);
PAINT SKYBLUE (-920 1232);
DISPLAY INVISIBLE (-920 1232);
FORCEPROP 1 LAST BODY_TYPE PLUMBING
J 0
(-920 1232);
DISPLAY 0.340426 (-920 1232);
PAINT GREEN (-920 1232);
DISPLAY INVISIBLE (-920 1232);
FORCEPROP 1 LAST SIZE 1B
J 0
(-800 1225);
DISPLAY 0.872340 (-800 1225);
PAINT AQUA (-800 1225);
DISPLAY INVISIBLE (-800 1225);
FORCEPROP 2 LAST CDS_LIB mstr_symbols
J 0
(-875 1275);
PAINT ORANGE (-875 1275);
DISPLAY INVISIBLE (-875 1275);
FORCEPROP 1 LAST PATH I211
J 0
(-800 1275);
DISPLAY 0.872340 (-800 1275);
PAINT AQUA (-800 1275);
DISPLAY INVISIBLE (-800 1275);
FORCEPROP 1 LAST HDL_POWER GND
J 0
(-875 1425);
DISPLAY 0.872340 (-875 1425);
PAINT GREEN (-875 1425);
DISPLAY INVISIBLE (-875 1425);
FORCEADD RES..2
(-1900 1650);
FORCEPROP 1 LAST PACK_TYPE 0402
J 0
(-1860 1475);
DISPLAY 0.617021 (-1860 1475);
PAINT SKYBLUE (-1860 1475);
FORCEPROP 1 LAST PART_NUMBER G21796-016
J 0
(-1860 1525);
DISPLAY 0.617021 (-1860 1525);
PAINT BLUE (-1860 1525);
FORCEPROP 1 LASTPIN (-1900 1550) $PN 2
J 0
(-1895 1560);
DISPLAY 0.617021 (-1895 1560);
PAINT ORANGE (-1895 1560);
FORCEPROP 1 LASTPIN (-1900 1750) $PN 1
J 0
(-1895 1712);
DISPLAY 0.617021 (-1895 1712);
PAINT ORANGE (-1895 1712);
FORCEPROP 1 LAST TOLERANCE 1%
J 0
(-1855 1675);
DISPLAY 0.617021 (-1855 1675);
PAINT SKYBLUE (-1855 1675);
FORCEPROP 1 LAST WATTAGE 1/16W
J 0
(-1860 1625);
DISPLAY 0.617021 (-1860 1625);
PAINT SKYBLUE (-1860 1625);
FORCEPROP 1 LAST MATERIAL CHIP
J 0
(-1860 1575);
DISPLAY 0.617021 (-1860 1575);
PAINT SKYBLUE (-1860 1575);
FORCEPROP 1 LAST VALUE 10.0K
J 0
(-1855 1725);
DISPLAY 0.617021 (-1855 1725);
PAINT SKYBLUE (-1855 1725);
FORCEPROP 1 LAST LOCATION R9E13
J 0
(-1855 1775);
DISPLAY 0.617021 (-1855 1775);
PAINT AQUA (-1855 1775);
FORCEPROP 2 LAST CDS_LIB mstr_discrete
J 0
(-1900 1650);
PAINT ORANGE (-1900 1650);
DISPLAY INVISIBLE (-1900 1650);
FORCEPROP 2 LAST CDS_LOCATION R9E13
J 0
(-1855 1775);
DISPLAY 0.617021 (-1855 1775);
PAINT AQUA (-1855 1775);
DISPLAY INVISIBLE (-1855 1775);
FORCEPROP 1 LAST PATH I212
J 0
(-1850 1825);
DISPLAY 0.978723 (-1850 1825);
PAINT WHITE (-1850 1825);
DISPLAY INVISIBLE (-1850 1825);
FORCEPROP 2 LAST ROOM NIC_SPRV
J 0
(-1850 1825);
DISPLAY 1.021277 (-1850 1825);
PAINT ORANGE (-1850 1825);
DISPLAY INVISIBLE (-1850 1825);
FORCEPROP 2 LAST BOM_COST NT_GBE_BASE
J 0
(-1850 1875);
DISPLAY 1.021277 (-1850 1875);
PAINT ORANGE (-1850 1875);
DISPLAY INVISIBLE (-1850 1875);
FORCEPROP 2 LAST CDS_SEC 1
J 0
(-1850 1875);
PAINT MONO (-1850 1875);
DISPLAY INVISIBLE (-1850 1875);
FORCEPROP 2 LAST $SEC 1
J 0
(-1850 1875);
PAINT MONO (-1850 1875);
DISPLAY INVISIBLE (-1850 1875);
FORCEADD RES..2
(-2875 1525);
FORCEPROP 1 LASTPIN (-2875 1425) $PN 2
J 0
(-2870 1435);
DISPLAY 0.617021 (-2870 1435);
PAINT ORANGE (-2870 1435);
FORCEPROP 1 LAST WATTAGE 1/16W
J 0
(-2835 1500);
DISPLAY 0.617021 (-2835 1500);
PAINT SKYBLUE (-2835 1500);
FORCEPROP 1 LAST MATERIAL CHIP
J 0
(-2835 1450);
DISPLAY 0.617021 (-2835 1450);
PAINT SKYBLUE (-2835 1450);
FORCEPROP 1 LAST PACK_TYPE 0402
J 0
(-2835 1350);
DISPLAY 0.617021 (-2835 1350);
PAINT SKYBLUE (-2835 1350);
FORCEPROP 1 LASTPIN (-2875 1625) $PN 1
J 0
(-2870 1587);
DISPLAY 0.617021 (-2870 1587);
PAINT ORANGE (-2870 1587);
FORCEPROP 1 LAST LOCATION R1R12
J 0
(-2830 1650);
DISPLAY 0.617021 (-2830 1650);
PAINT AQUA (-2830 1650);
FORCEPROP 1 LAST VALUE 10.0K
J 0
(-2830 1600);
DISPLAY 0.617021 (-2830 1600);
PAINT SKYBLUE (-2830 1600);
FORCEPROP 1 LAST TOLERANCE 1%
J 0
(-2830 1550);
DISPLAY 0.617021 (-2830 1550);
PAINT SKYBLUE (-2830 1550);
FORCEPROP 1 LAST PART_NUMBER G21796-016
J 0
(-2835 1400);
DISPLAY 0.617021 (-2835 1400);
PAINT BLUE (-2835 1400);
FORCEPROP 2 LAST CDS_LIB mstr_discrete
J 0
(-2875 1525);
PAINT ORANGE (-2875 1525);
DISPLAY INVISIBLE (-2875 1525);
FORCEPROP 2 LAST BOM_COST NT_GBE_BASE
J 0
(-2825 1750);
DISPLAY 1.021277 (-2825 1750);
PAINT ORANGE (-2825 1750);
DISPLAY INVISIBLE (-2825 1750);
FORCEPROP 2 LAST CDS_SEC 1
J 0
(-2825 1750);
PAINT MONO (-2825 1750);
DISPLAY INVISIBLE (-2825 1750);
FORCEPROP 2 LAST $SEC 1
J 0
(-2825 1750);
PAINT MONO (-2825 1750);
DISPLAY INVISIBLE (-2825 1750);
FORCEPROP 2 LAST CDS_LOCATION R1R12
J 0
(-2830 1650);
DISPLAY 0.617021 (-2830 1650);
PAINT AQUA (-2830 1650);
DISPLAY INVISIBLE (-2830 1650);
FORCEPROP 1 LAST PATH I213
J 0
(-2825 1700);
DISPLAY 0.978723 (-2825 1700);
PAINT WHITE (-2825 1700);
DISPLAY INVISIBLE (-2825 1700);
FORCEPROP 2 LAST ROOM NIC_SPRV
J 0
(-2825 1700);
DISPLAY 1.021277 (-2825 1700);
PAINT ORANGE (-2825 1700);
DISPLAY INVISIBLE (-2825 1700);
FORCEADD RES..2
(-875 1550);
FORCEPROP 1 LASTPIN (-875 1450) $PN 2
J 0
(-870 1460);
DISPLAY 0.617021 (-870 1460);
PAINT ORANGE (-870 1460);
FORCEPROP 1 LAST PART_NUMBER G21796-016
J 0
(-835 1425);
DISPLAY 0.617021 (-835 1425);
PAINT BLUE (-835 1425);
FORCEPROP 1 LAST PACK_TYPE 0402
J 0
(-835 1375);
DISPLAY 0.617021 (-835 1375);
PAINT SKYBLUE (-835 1375);
FORCEPROP 1 LAST MATERIAL CHIP
J 0
(-835 1475);
DISPLAY 0.617021 (-835 1475);
PAINT SKYBLUE (-835 1475);
FORCEPROP 1 LAST WATTAGE 1/16W
J 0
(-835 1525);
DISPLAY 0.617021 (-835 1525);
PAINT SKYBLUE (-835 1525);
FORCEPROP 1 LASTPIN (-875 1650) $PN 1
J 0
(-870 1612);
DISPLAY 0.617021 (-870 1612);
PAINT ORANGE (-870 1612);
FORCEPROP 1 LAST TOLERANCE 1%
J 0
(-830 1575);
DISPLAY 0.617021 (-830 1575);
PAINT SKYBLUE (-830 1575);
FORCEPROP 1 LAST VALUE 10.0K
J 0
(-830 1625);
DISPLAY 0.617021 (-830 1625);
PAINT SKYBLUE (-830 1625);
FORCEPROP 1 LAST LOCATION R1T1
J 0
(-830 1675);
DISPLAY 0.617021 (-830 1675);
PAINT AQUA (-830 1675);
FORCEPROP 2 LAST CDS_LIB mstr_discrete
J 0
(-875 1550);
PAINT ORANGE (-875 1550);
DISPLAY INVISIBLE (-875 1550);
FORCEPROP 2 LAST ROOM NIC_SPRV
J 0
(-825 1725);
DISPLAY 1.021277 (-825 1725);
PAINT ORANGE (-825 1725);
DISPLAY INVISIBLE (-825 1725);
FORCEPROP 2 LAST CDS_LOCATION R1T1
J 0
(-830 1675);
DISPLAY 0.617021 (-830 1675);
PAINT AQUA (-830 1675);
DISPLAY INVISIBLE (-830 1675);
FORCEPROP 1 LAST PATH I214
J 0
(-825 1725);
DISPLAY 0.978723 (-825 1725);
PAINT WHITE (-825 1725);
DISPLAY INVISIBLE (-825 1725);
FORCEPROP 2 LAST $SEC 1
J 0
(-825 1775);
PAINT MONO (-825 1775);
DISPLAY INVISIBLE (-825 1775);
FORCEPROP 2 LAST CDS_SEC 1
J 0
(-825 1775);
PAINT MONO (-825 1775);
DISPLAY INVISIBLE (-825 1775);
FORCEPROP 2 LAST BOM_COST NT_GBE_BASE
J 0
(-825 1775);
DISPLAY 1.021277 (-825 1775);
PAINT ORANGE (-825 1775);
DISPLAY INVISIBLE (-825 1775);
FORCEADD OFFPAGE..4
(-2350 3025);
FORCEPROP 2 LAST $XR0 159 
J 0
(-2164 3025);
DISPLAY 0.638298 (-2164 3025);
PAINT MONO (-2164 3025);
FORCEPROP 1 LAST COMMENT_BODY TRUE
J 0
(-2375 2925);
DISPLAY 0.872340 (-2375 2925);
PAINT GREEN (-2375 2925);
DISPLAY INVISIBLE (-2375 2925);
FORCEPROP 2 LAST CDS_LIB mstr_standard
J 0
(-2350 3025);
PAINT ORANGE (-2350 3025);
DISPLAY INVISIBLE (-2350 3025);
FORCEPROP 2 LAST PATH I218
J 0
(-2300 3100);
DISPLAY 1.021277 (-2300 3100);
PAINT ORANGE (-2300 3100);
DISPLAY INVISIBLE (-2300 3100);
FORCEPROP 1 LAST OFFPAGE TRUE
J 0
(-2025 2900);
DISPLAY 0.872340 (-2025 2900);
PAINT GREEN (-2025 2900);
DISPLAY INVISIBLE (-2025 2900);
FORCEADD OFFPAGE..4
(-2350 2975);
FORCEPROP 2 LAST $XR0 159 
J 0
(-2164 2975);
DISPLAY 0.638298 (-2164 2975);
PAINT MONO (-2164 2975);
FORCEPROP 1 LAST COMMENT_BODY TRUE
J 0
(-2375 2875);
DISPLAY 0.872340 (-2375 2875);
PAINT GREEN (-2375 2875);
DISPLAY INVISIBLE (-2375 2875);
FORCEPROP 2 LAST CDS_LIB mstr_standard
J 0
(-2350 2975);
PAINT ORANGE (-2350 2975);
DISPLAY INVISIBLE (-2350 2975);
FORCEPROP 2 LAST PATH I219
J 0
(-2175 3050);
DISPLAY 1.021277 (-2175 3050);
PAINT ORANGE (-2175 3050);
DISPLAY INVISIBLE (-2175 3050);
FORCEPROP 1 LAST OFFPAGE TRUE
J 0
(-2025 2850);
DISPLAY 0.872340 (-2025 2850);
PAINT GREEN (-2025 2850);
DISPLAY INVISIBLE (-2025 2850);
FORCEADD OFFPAGE..2
(-2350 2925);
FORCEPROP 2 LAST $XR0 139 
J 0
(-2161 2925);
DISPLAY 0.638298 (-2161 2925);
PAINT MONO (-2161 2925);
FORCEPROP 2 LAST $XR1 119 
J 0
(-2041 2925);
DISPLAY 0.638298 (-2041 2925);
PAINT MONO (-2041 2925);
FORCEPROP 2 LAST $XR2 146 
J 0
(-1921 2925);
DISPLAY 0.638298 (-1921 2925);
PAINT MONO (-1921 2925);
FORCEPROP 1 LAST COMMENT_BODY TRUE
J 0
(-2395 2830);
DISPLAY 0.872340 (-2395 2830);
PAINT GREEN (-2395 2830);
DISPLAY INVISIBLE (-2395 2830);
FORCEPROP 2 LAST CDS_LIB mstr_standard
J 0
(-2350 2925);
PAINT ORANGE (-2350 2925);
DISPLAY INVISIBLE (-2350 2925);
FORCEPROP 2 LAST PATH I220
J 0
(-2175 3000);
DISPLAY 1.021277 (-2175 3000);
PAINT ORANGE (-2175 3000);
DISPLAY INVISIBLE (-2175 3000);
FORCEPROP 1 LAST OFFPAGE TRUE
J 0
(-2025 2800);
DISPLAY 0.872340 (-2025 2800);
PAINT GREEN (-2025 2800);
DISPLAY INVISIBLE (-2025 2800);
FORCEADD OFFPAGE..1
(-6750 2475);
FORCEPROP 2 LAST $XR0 147 
J 0
(-7002 2475);
DISPLAY 0.638298 (-7002 2475);
PAINT MONO (-7002 2475);
FORCEPROP 2 LAST $XR1 121 
J 0
(-7122 2475);
DISPLAY 0.638298 (-7122 2475);
PAINT MONO (-7122 2475);
FORCEPROP 2 LAST CDS_LIB mstr_standard
J 0
(-6750 2475);
PAINT ORANGE (-6750 2475);
DISPLAY INVISIBLE (-6750 2475);
FORCEPROP 2 LAST PATH I223
J 0
(-6700 2550);
DISPLAY 1.021277 (-6700 2550);
PAINT ORANGE (-6700 2550);
DISPLAY INVISIBLE (-6700 2550);
FORCEPROP 1 LAST OFFPAGE TRUE
J 0
(-6425 2350);
DISPLAY 0.872340 (-6425 2350);
PAINT GREEN (-6425 2350);
DISPLAY INVISIBLE (-6425 2350);
FORCEPROP 1 LAST COMMENT_BODY TRUE
J 0
(-6625 2375);
DISPLAY 0.872340 (-6625 2375);
PAINT GREEN (-6625 2375);
DISPLAY INVISIBLE (-6625 2375);
FORCEADD OFFPAGE..1
(-6750 2525);
FORCEPROP 2 LAST $XR0 147 
J 0
(-7002 2525);
DISPLAY 0.638298 (-7002 2525);
PAINT MONO (-7002 2525);
FORCEPROP 2 LAST $XR1 121 
J 0
(-7122 2525);
DISPLAY 0.638298 (-7122 2525);
PAINT MONO (-7122 2525);
FORCEPROP 2 LAST CDS_LIB mstr_standard
J 0
(-6750 2525);
PAINT ORANGE (-6750 2525);
DISPLAY INVISIBLE (-6750 2525);
FORCEPROP 2 LAST PATH I224
J 0
(-6700 2600);
DISPLAY 1.021277 (-6700 2600);
PAINT ORANGE (-6700 2600);
DISPLAY INVISIBLE (-6700 2600);
FORCEPROP 1 LAST OFFPAGE TRUE
J 0
(-6425 2400);
DISPLAY 0.872340 (-6425 2400);
PAINT GREEN (-6425 2400);
DISPLAY INVISIBLE (-6425 2400);
FORCEPROP 1 LAST COMMENT_BODY TRUE
J 0
(-6625 2425);
DISPLAY 0.872340 (-6625 2425);
PAINT GREEN (-6625 2425);
DISPLAY INVISIBLE (-6625 2425);
FORCEADD RES..1
(-2400 2675);
FORCEPROP 1 LAST MATERIAL CHIP
J 0
(-2625 2625);
DISPLAY 0.617021 (-2625 2625);
PAINT SKYBLUE (-2625 2625);
FORCEPROP 1 LAST PART_NUMBER G21796-250
J 0
(-2850 2625);
DISPLAY 0.617021 (-2850 2625);
PAINT BLUE (-2850 2625);
FORCEPROP 1 LAST VALUE 22.1
J 2
(-2425 2625);
DISPLAY 0.617021 (-2425 2625);
PAINT SKYBLUE (-2425 2625);
FORCEPROP 1 LAST TOLERANCE 1.0%
J 0
(-2350 2625);
DISPLAY 0.617021 (-2350 2625);
PAINT SKYBLUE (-2350 2625);
FORCEPROP 1 LAST LOCATION R9F1
J 0
(-2350 2675);
DISPLAY 0.617021 (-2350 2675);
PAINT AQUA (-2350 2675);
FORCEPROP 1 LAST WATTAGE 1/16W
J 2
(-2125 2625);
DISPLAY 0.617021 (-2125 2625);
PAINT SKYBLUE (-2125 2625);
FORCEPROP 1 LAST PACK_TYPE 0402
J 0
(-2100 2625);
DISPLAY 0.617021 (-2100 2625);
PAINT SKYBLUE (-2100 2625);
FORCEPROP 1 LASTPIN (-2500 2675) $PN 1
J 0
(-2488 2687);
DISPLAY 0.787234 (-2488 2687);
PAINT ORANGE (-2488 2687);
DISPLAY INVISIBLE (-2488 2687);
FORCEPROP 2 LAST CDS_LOCATION R9F1
J 0
(-2350 2675);
DISPLAY 0.617021 (-2350 2675);
PAINT AQUA (-2350 2675);
DISPLAY INVISIBLE (-2350 2675);
FORCEPROP 2 LAST CDS_LIB mstr_discrete
J 0
(-2400 2675);
PAINT ORANGE (-2400 2675);
DISPLAY INVISIBLE (-2400 2675);
FORCEPROP 1 LASTPIN (-2300 2675) $PN 2
J 0
(-2338 2687);
DISPLAY 0.787234 (-2338 2687);
PAINT ORANGE (-2338 2687);
DISPLAY INVISIBLE (-2338 2687);
FORCEPROP 1 LAST PATH I225
J 0
(-2450 2825);
DISPLAY 0.978723 (-2450 2825);
PAINT WHITE (-2450 2825);
DISPLAY INVISIBLE (-2450 2825);
FORCEPROP 2 LAST $SEC 1
J 0
(-2450 2875);
DISPLAY 0.680851 (-2450 2875);
PAINT MONO (-2450 2875);
DISPLAY INVISIBLE (-2450 2875);
FORCEPROP 2 LAST CDS_SEC 1
J 0
(-2450 2875);
DISPLAY 1.021277 (-2450 2875);
PAINT ORANGE (-2450 2875);
DISPLAY INVISIBLE (-2450 2875);
FORCEADD OFFPAGE..2
(-875 2675);
FORCEPROP 2 LAST $XR0 121 
J 0
(-686 2675);
DISPLAY 0.638298 (-686 2675);
PAINT MONO (-686 2675);
FORCEPROP 2 LAST $XR1 139 
J 0
(-566 2675);
DISPLAY 0.638298 (-566 2675);
PAINT MONO (-566 2675);
FORCEPROP 2 LAST $XR2 147 
J 0
(-446 2675);
DISPLAY 0.638298 (-446 2675);
PAINT MONO (-446 2675);
FORCEPROP 1 LAST OFFPAGE TRUE
J 0
(-550 2550);
DISPLAY 0.872340 (-550 2550);
PAINT GREEN (-550 2550);
DISPLAY INVISIBLE (-550 2550);
FORCEPROP 1 LAST COMMENT_BODY TRUE
J 0
(-920 2580);
DISPLAY 0.872340 (-920 2580);
PAINT GREEN (-920 2580);
DISPLAY INVISIBLE (-920 2580);
FORCEPROP 2 LAST CDS_LIB mstr_standard
J 0
(-875 2675);
PAINT ORANGE (-875 2675);
DISPLAY INVISIBLE (-875 2675);
FORCEPROP 2 LAST PATH I226
J 0
(-825 2750);
DISPLAY 1.021277 (-825 2750);
PAINT ORANGE (-825 2750);
DISPLAY INVISIBLE (-825 2750);
FORCEADD OFFPAGE..1
(-6050 2725);
FORCEPROP 2 LAST $XR0 101 
J 0
(-6302 2725);
DISPLAY 0.638298 (-6302 2725);
PAINT MONO (-6302 2725);
FORCEPROP 2 LAST $XR1 139 
J 0
(-6422 2725);
DISPLAY 0.638298 (-6422 2725);
PAINT MONO (-6422 2725);
FORCEPROP 2 LAST CDS_LIB mstr_standard
J 0
(-6050 2725);
PAINT ORANGE (-6050 2725);
DISPLAY INVISIBLE (-6050 2725);
FORCEPROP 1 LAST COMMENT_BODY TRUE
J 0
(-5925 2625);
DISPLAY 0.872340 (-5925 2625);
PAINT GREEN (-5925 2625);
DISPLAY INVISIBLE (-5925 2625);
FORCEPROP 2 LAST PATH I227
J 0
(-6000 2800);
DISPLAY 1.021277 (-6000 2800);
PAINT ORANGE (-6000 2800);
DISPLAY INVISIBLE (-6000 2800);
FORCEPROP 1 LAST OFFPAGE TRUE
J 0
(-5725 2600);
DISPLAY 0.872340 (-5725 2600);
PAINT GREEN (-5725 2600);
DISPLAY INVISIBLE (-5725 2600);
FORCEADD RES..1
(-2275 2525);
FORCEPROP 1 LAST MATERIAL CHIP
J 2
(-2375 2525);
DISPLAY 0.617021 (-2375 2525);
PAINT SKYBLUE (-2375 2525);
FORCEPROP 1 LAST LOCATION R9E19
J 0
(-2325 2475);
DISPLAY 0.617021 (-2325 2475);
PAINT AQUA (-2325 2475);
FORCEPROP 1 LAST TOLERANCE 1.0%
J 2
(-2125 2475);
DISPLAY 0.617021 (-2125 2475);
PAINT SKYBLUE (-2125 2475);
FORCEPROP 1 LAST VALUE 22.1
J 2
(-2050 2525);
DISPLAY 0.617021 (-2050 2525);
PAINT SKYBLUE (-2050 2525);
FORCEPROP 1 LASTPIN (-2375 2525) $PN 1
J 0
(-2363 2537);
DISPLAY 0.617021 (-2363 2537);
PAINT ORANGE (-2363 2537);
FORCEPROP 1 LASTPIN (-2175 2525) $PN 2
J 0
(-2213 2537);
DISPLAY 0.617021 (-2213 2537);
PAINT ORANGE (-2213 2537);
FORCEPROP 2 LAST CDS_LOCATION R9E19
J 0
(-2325 2475);
DISPLAY 0.617021 (-2325 2475);
PAINT AQUA (-2325 2475);
DISPLAY INVISIBLE (-2325 2475);
FORCEPROP 1 LAST WATTAGE 1/16W
J 2
(-2300 2375);
DISPLAY 0.978723 (-2300 2375);
PAINT SKYBLUE (-2300 2375);
DISPLAY INVISIBLE (-2300 2375);
FORCEPROP 2 LAST CDS_LIB mstr_discrete
J 0
(-2275 2525);
PAINT ORANGE (-2275 2525);
DISPLAY INVISIBLE (-2275 2525);
FORCEPROP 1 LAST PART_NUMBER G21796-250
J 0
(-2325 2625);
DISPLAY 0.978723 (-2325 2625);
PAINT BLUE (-2325 2625);
DISPLAY INVISIBLE (-2325 2625);
FORCEPROP 2 LAST SEC_TYPE 0402
J 0
(-2325 2725);
DISPLAY 1.021277 (-2325 2725);
PAINT ORANGE (-2325 2725);
DISPLAY INVISIBLE (-2325 2725);
FORCEPROP 2 LAST SEC 1
J 0
(-2325 2725);
DISPLAY 0.680851 (-2325 2725);
PAINT MONO (-2325 2725);
DISPLAY INVISIBLE (-2325 2725);
FORCEPROP 1 LAST PATH I228
J 0
(-2325 2675);
DISPLAY 0.978723 (-2325 2675);
PAINT WHITE (-2325 2675);
DISPLAY INVISIBLE (-2325 2675);
FORCEPROP 1 LAST PACK_TYPE 0402
J 0
(-2025 2375);
DISPLAY 0.978723 (-2025 2375);
PAINT SKYBLUE (-2025 2375);
DISPLAY INVISIBLE (-2025 2375);
FORCEPROP 2 LAST ROOM BMC
J 0
(-2000 2525);
DISPLAY 1.021277 (-2000 2525);
PAINT ORANGE (-2000 2525);
DISPLAY INVISIBLE (-2000 2525);
FORCEPROP 2 LAST BOM_COST SM_CONTROLLER
J 0
(-2000 2575);
DISPLAY 1.021277 (-2000 2575);
PAINT ORANGE (-2000 2575);
DISPLAY INVISIBLE (-2000 2575);
FORCEADD RES..1
(-1750 2475);
FORCEPROP 1 LASTPIN (-1850 2475) $PN 1
J 0
(-1838 2487);
DISPLAY 0.617021 (-1838 2487);
PAINT ORANGE (-1838 2487);
FORCEPROP 1 LAST MATERIAL CHIP
J 2
(-1875 2425);
DISPLAY 0.617021 (-1875 2425);
PAINT SKYBLUE (-1875 2425);
FORCEPROP 1 LAST LOCATION R9E17
J 0
(-1800 2425);
DISPLAY 0.617021 (-1800 2425);
PAINT AQUA (-1800 2425);
FORCEPROP 1 LASTPIN (-1650 2475) $PN 2
J 0
(-1688 2487);
DISPLAY 0.617021 (-1688 2487);
PAINT ORANGE (-1688 2487);
FORCEPROP 1 LAST TOLERANCE 1.0%
J 2
(-1600 2425);
DISPLAY 0.617021 (-1600 2425);
PAINT SKYBLUE (-1600 2425);
FORCEPROP 1 LAST VALUE 22.1
J 2
(-1475 2425);
DISPLAY 0.617021 (-1475 2425);
PAINT SKYBLUE (-1475 2425);
FORCEPROP 2 LAST CDS_LOCATION R9E17
J 0
(-1800 2425);
DISPLAY 0.617021 (-1800 2425);
PAINT AQUA (-1800 2425);
DISPLAY INVISIBLE (-1800 2425);
FORCEPROP 2 LAST CDS_LIB mstr_discrete
J 0
(-1750 2475);
PAINT ORANGE (-1750 2475);
DISPLAY INVISIBLE (-1750 2475);
FORCEPROP 1 LAST WATTAGE 1/16W
J 2
(-1775 2325);
DISPLAY 0.978723 (-1775 2325);
PAINT SKYBLUE (-1775 2325);
DISPLAY INVISIBLE (-1775 2325);
FORCEPROP 1 LAST PATH I229
J 0
(-1800 2625);
DISPLAY 0.978723 (-1800 2625);
PAINT WHITE (-1800 2625);
DISPLAY INVISIBLE (-1800 2625);
FORCEPROP 2 LAST SEC 1
J 0
(-1800 2675);
DISPLAY 0.680851 (-1800 2675);
PAINT MONO (-1800 2675);
DISPLAY INVISIBLE (-1800 2675);
FORCEPROP 2 LAST SEC_TYPE 0402
J 0
(-1800 2675);
DISPLAY 1.021277 (-1800 2675);
PAINT ORANGE (-1800 2675);
DISPLAY INVISIBLE (-1800 2675);
FORCEPROP 1 LAST PART_NUMBER G21796-250
J 0
(-1800 2575);
DISPLAY 0.978723 (-1800 2575);
PAINT BLUE (-1800 2575);
DISPLAY INVISIBLE (-1800 2575);
FORCEPROP 1 LAST PACK_TYPE 0402
J 0
(-1500 2325);
DISPLAY 0.978723 (-1500 2325);
PAINT SKYBLUE (-1500 2325);
DISPLAY INVISIBLE (-1500 2325);
FORCEPROP 2 LAST ROOM BMC
J 0
(-1475 2475);
DISPLAY 1.021277 (-1475 2475);
PAINT ORANGE (-1475 2475);
DISPLAY INVISIBLE (-1475 2475);
FORCEPROP 2 LAST BOM_COST SM_CONTROLLER
J 0
(-1475 2525);
DISPLAY 1.021277 (-1475 2525);
PAINT ORANGE (-1475 2525);
DISPLAY INVISIBLE (-1475 2525);
FORCEADD OFFPAGE..2
(-875 2525);
FORCEPROP 2 LAST $XR0 121 
J 0
(-686 2525);
DISPLAY 0.638298 (-686 2525);
PAINT MONO (-686 2525);
FORCEPROP 2 LAST $XR1 147 
J 0
(-566 2525);
DISPLAY 0.638298 (-566 2525);
PAINT MONO (-566 2525);
FORCEPROP 1 LAST COMMENT_BODY TRUE
J 0
(-920 2430);
DISPLAY 0.872340 (-920 2430);
PAINT GREEN (-920 2430);
DISPLAY INVISIBLE (-920 2430);
FORCEPROP 1 LAST OFFPAGE TRUE
J 0
(-550 2400);
DISPLAY 0.872340 (-550 2400);
PAINT GREEN (-550 2400);
DISPLAY INVISIBLE (-550 2400);
FORCEPROP 2 LAST CDS_LIB mstr_standard
J 0
(-875 2525);
PAINT ORANGE (-875 2525);
DISPLAY INVISIBLE (-875 2525);
FORCEPROP 2 LAST PATH I230
J 0
(-825 2600);
DISPLAY 1.021277 (-825 2600);
PAINT ORANGE (-825 2600);
DISPLAY INVISIBLE (-825 2600);
FORCEADD OFFPAGE..2
(-875 2475);
FORCEPROP 2 LAST $XR0 121 
J 0
(-686 2475);
DISPLAY 0.638298 (-686 2475);
PAINT MONO (-686 2475);
FORCEPROP 2 LAST $XR1 147 
J 0
(-566 2475);
DISPLAY 0.638298 (-566 2475);
PAINT MONO (-566 2475);
FORCEPROP 1 LAST COMMENT_BODY TRUE
J 0
(-920 2380);
DISPLAY 0.872340 (-920 2380);
PAINT GREEN (-920 2380);
DISPLAY INVISIBLE (-920 2380);
FORCEPROP 2 LAST CDS_LIB mstr_standard
J 0
(-875 2475);
PAINT ORANGE (-875 2475);
DISPLAY INVISIBLE (-875 2475);
FORCEPROP 1 LAST OFFPAGE TRUE
J 0
(-550 2350);
DISPLAY 0.872340 (-550 2350);
PAINT GREEN (-550 2350);
DISPLAY INVISIBLE (-550 2350);
FORCEPROP 2 LAST PATH I231
J 0
(-700 2550);
DISPLAY 1.021277 (-700 2550);
PAINT ORANGE (-700 2550);
DISPLAY INVISIBLE (-700 2550);
FORCEADD OFFPAGE..1
(-6050 2625);
FORCEPROP 2 LAST $XR0 121 
J 0
(-6302 2625);
DISPLAY 0.638298 (-6302 2625);
PAINT MONO (-6302 2625);
FORCEPROP 2 LAST $XR1 125 
J 0
(-6422 2625);
DISPLAY 0.638298 (-6422 2625);
PAINT MONO (-6422 2625);
FORCEPROP 1 LAST OFFPAGE TRUE
J 0
(-5725 2500);
DISPLAY 0.872340 (-5725 2500);
PAINT GREEN (-5725 2500);
DISPLAY INVISIBLE (-5725 2500);
FORCEPROP 1 LAST COMMENT_BODY TRUE
J 0
(-5925 2525);
DISPLAY 0.872340 (-5925 2525);
PAINT GREEN (-5925 2525);
DISPLAY INVISIBLE (-5925 2525);
FORCEPROP 2 LAST CDS_LIB mstr_standard
J 0
(-6050 2625);
PAINT MONO (-6050 2625);
DISPLAY INVISIBLE (-6050 2625);
FORCEPROP 2 LAST PATH I233
J 0
(-6000 2700);
DISPLAY 1.021277 (-6000 2700);
PAINT ORANGE (-6000 2700);
DISPLAY INVISIBLE (-6000 2700);
FORCEADD RES..1
(-2075 2725);
FORCEPROP 1 LAST VALUE 33.2
J 2
(-2125 2675);
DISPLAY 0.617021 (-2125 2675);
PAINT SKYBLUE (-2125 2675);
FORCEPROP 1 LASTPIN (-2175 2725) $PN 1
J 0
(-2163 2737);
DISPLAY 0.617021 (-2163 2737);
PAINT ORANGE (-2163 2737);
FORCEPROP 1 LASTPIN (-1975 2725) $PN 2
J 0
(-2013 2737);
DISPLAY 0.617021 (-2013 2737);
PAINT ORANGE (-2013 2737);
FORCEPROP 1 LAST TOLERANCE 1%
J 0
(-2025 2675);
DISPLAY 0.617021 (-2025 2675);
PAINT SKYBLUE (-2025 2675);
FORCEPROP 1 LAST LOCATION R9E16
J 0
(-1875 2675);
DISPLAY 0.617021 (-1875 2675);
PAINT AQUA (-1875 2675);
FORCEPROP 1 LAST PART_NUMBER G21796-074
J 0
(-1975 2725);
DISPLAY 0.617021 (-1975 2725);
PAINT BLUE (-1975 2725);
FORCEPROP 1 LAST MATERIAL CHIP
J 0
(-2075 2575);
DISPLAY 0.617021 (-2075 2575);
PAINT SKYBLUE (-2075 2575);
DISPLAY INVISIBLE (-2075 2575);
FORCEPROP 1 LAST WATTAGE 1/16W
J 2
(-2100 2575);
DISPLAY 0.617021 (-2100 2575);
PAINT SKYBLUE (-2100 2575);
DISPLAY INVISIBLE (-2100 2575);
FORCEPROP 2 LAST CDS_LIB mstr_discrete
J 0
(-2075 2725);
PAINT ORANGE (-2075 2725);
DISPLAY INVISIBLE (-2075 2725);
FORCEPROP 1 LAST PATH I235
J 0
(-2125 2875);
DISPLAY 0.978723 (-2125 2875);
PAINT WHITE (-2125 2875);
DISPLAY INVISIBLE (-2125 2875);
FORCEPROP 2 LAST SEC 1
J 0
(-2125 2925);
DISPLAY 0.680851 (-2125 2925);
PAINT MONO (-2125 2925);
DISPLAY INVISIBLE (-2125 2925);
FORCEPROP 2 LAST SEC_TYPE 0402
J 0
(-2125 2925);
DISPLAY 1.021277 (-2125 2925);
PAINT ORANGE (-2125 2925);
DISPLAY INVISIBLE (-2125 2925);
FORCEPROP 2 LAST CDS_LOCATION R9E16
J 0
(-1875 2675);
DISPLAY 0.617021 (-1875 2675);
PAINT AQUA (-1875 2675);
DISPLAY INVISIBLE (-1875 2675);
FORCEPROP 1 LAST PACK_TYPE 0402
J 0
(-1825 2575);
DISPLAY 0.617021 (-1825 2575);
PAINT SKYBLUE (-1825 2575);
DISPLAY INVISIBLE (-1825 2575);
FORCEPROP 0 LAST ROOM SB
J 0
(-2025 2825);
DISPLAY 1.021277 (-2025 2825);
PAINT ORANGE (-2025 2825);
DISPLAY INVISIBLE (-2025 2825);
FORCEADD OFFPAGE..2
(-875 2725);
FORCEPROP 2 LAST $XR0 121 
J 0
(-686 2725);
DISPLAY 0.638298 (-686 2725);
PAINT MONO (-686 2725);
FORCEPROP 1 LAST COMMENT_BODY TRUE
J 0
(-920 2630);
DISPLAY 0.872340 (-920 2630);
PAINT GREEN (-920 2630);
DISPLAY INVISIBLE (-920 2630);
FORCEPROP 2 LAST CDS_LIB mstr_standard
J 0
(-875 2725);
PAINT ORANGE (-875 2725);
DISPLAY INVISIBLE (-875 2725);
FORCEPROP 1 LAST OFFPAGE TRUE
J 0
(-550 2600);
DISPLAY 0.872340 (-550 2600);
PAINT GREEN (-550 2600);
DISPLAY INVISIBLE (-550 2600);
FORCEPROP 2 LAST PATH I236
J 0
(-700 2800);
DISPLAY 1.021277 (-700 2800);
PAINT ORANGE (-700 2800);
DISPLAY INVISIBLE (-700 2800);
FORCEADD RES..1
(-5600 4025);
FORCEPROP 1 LAST PART_NUMBER G22178-002
J 0
(-5950 3975);
DISPLAY 0.617021 (-5950 3975);
PAINT BLUE (-5950 3975);
FORCEPROP 1 LAST VALUE 0
J 2
(-5650 3975);
DISPLAY 0.617021 (-5650 3975);
PAINT SKYBLUE (-5650 3975);
FORCEPROP 1 LASTPIN (-5700 4025) $PN 1
J 0
(-5688 4037);
DISPLAY 0.617021 (-5688 4037);
PAINT ORANGE (-5688 4037);
FORCEPROP 1 LAST PACK_TYPE 0603
J 0
(-5525 3975);
DISPLAY 0.617021 (-5525 3975);
PAINT SKYBLUE (-5525 3975);
FORCEPROP 1 LASTPIN (-5500 4025) $PN 2
J 0
(-5538 4037);
DISPLAY 0.617021 (-5538 4037);
PAINT ORANGE (-5538 4037);
FORCEPROP 1 LAST LOCATION R1R15
J 0
(-5675 4075);
DISPLAY 0.617021 (-5675 4075);
PAINT AQUA (-5675 4075);
FORCEPROP 1 LAST TOLERANCE 5.0%
J 0
(-5600 3925);
DISPLAY 0.617021 (-5600 3925);
PAINT SKYBLUE (-5600 3925);
DISPLAY INVISIBLE (-5600 3925);
FORCEPROP 1 LAST MATERIAL CHIP
J 0
(-5600 3875);
DISPLAY 0.617021 (-5600 3875);
PAINT SKYBLUE (-5600 3875);
DISPLAY INVISIBLE (-5600 3875);
FORCEPROP 1 LAST WATTAGE 1/10W
J 2
(-5625 3875);
DISPLAY 0.617021 (-5625 3875);
PAINT SKYBLUE (-5625 3875);
DISPLAY INVISIBLE (-5625 3875);
FORCEPROP 2 LAST CDS_LIB mstr_discrete
J 0
(-5600 4025);
PAINT ORANGE (-5600 4025);
DISPLAY INVISIBLE (-5600 4025);
FORCEPROP 2 LAST CDS_LOCATION R1R15
J 0
(-5675 4075);
DISPLAY 0.617021 (-5675 4075);
PAINT AQUA (-5675 4075);
DISPLAY INVISIBLE (-5675 4075);
FORCEPROP 1 LAST PATH I237
J 0
(-5650 4175);
DISPLAY 0.978723 (-5650 4175);
PAINT WHITE (-5650 4175);
DISPLAY INVISIBLE (-5650 4175);
FORCEPROP 2 LAST SEC 1
J 0
(-5650 4225);
DISPLAY 0.680851 (-5650 4225);
PAINT MONO (-5650 4225);
DISPLAY INVISIBLE (-5650 4225);
FORCEPROP 2 LAST SEC_TYPE 0603
J 0
(-5650 4225);
DISPLAY 1.021277 (-5650 4225);
PAINT ORANGE (-5650 4225);
DISPLAY INVISIBLE (-5650 4225);
FORCEPROP 0 LAST ROOM NIC_SPRV
J 0
(-5500 4150);
DISPLAY 1.021277 (-5500 4150);
PAINT ORANGE (-5500 4150);
DISPLAY INVISIBLE (-5500 4150);
FORCEPROP 0 LAST BOM_COST NT_GBE_BASE
J 0
(-5500 4250);
DISPLAY 1.021277 (-5500 4250);
PAINT ORANGE (-5500 4250);
DISPLAY INVISIBLE (-5500 4250);
FORCEADD RES..1
(-5800 3875);
FORCEPROP 1 LASTPIN (-5900 3875) $PN 1
J 0
(-5888 3887);
DISPLAY 0.617021 (-5888 3887);
PAINT ORANGE (-5888 3887);
FORCEPROP 1 LAST PART_NUMBER G22178-002
J 0
(-6050 3925);
DISPLAY 0.617021 (-6050 3925);
PAINT BLUE (-6050 3925);
FORCEPROP 1 LAST VALUE 0
J 2
(-5850 3825);
DISPLAY 0.617021 (-5850 3825);
PAINT SKYBLUE (-5850 3825);
FORCEPROP 1 LASTPIN (-5700 3875) $PN 2
J 0
(-5738 3887);
DISPLAY 0.617021 (-5738 3887);
PAINT ORANGE (-5738 3887);
FORCEPROP 1 LAST PACK_TYPE 0603
J 0
(-5725 3825);
DISPLAY 0.617021 (-5725 3825);
PAINT SKYBLUE (-5725 3825);
FORCEPROP 1 LAST LOCATION R1T32
J 0
(-5700 3900);
DISPLAY 0.617021 (-5700 3900);
PAINT AQUA (-5700 3900);
FORCEPROP 1 LAST WATTAGE 1/10W
J 2
(-5825 3725);
DISPLAY 0.617021 (-5825 3725);
PAINT SKYBLUE (-5825 3725);
DISPLAY INVISIBLE (-5825 3725);
FORCEPROP 1 LAST MATERIAL CHIP
J 0
(-5800 3725);
DISPLAY 0.617021 (-5800 3725);
PAINT SKYBLUE (-5800 3725);
DISPLAY INVISIBLE (-5800 3725);
FORCEPROP 1 LAST TOLERANCE 5.0%
J 0
(-5800 3775);
DISPLAY 0.617021 (-5800 3775);
PAINT SKYBLUE (-5800 3775);
DISPLAY INVISIBLE (-5800 3775);
FORCEPROP 1 LAST PATH I238
J 0
(-5850 4025);
DISPLAY 0.978723 (-5850 4025);
PAINT WHITE (-5850 4025);
DISPLAY INVISIBLE (-5850 4025);
FORCEPROP 2 LAST CDS_LIB mstr_discrete
J 0
(-5800 3875);
PAINT ORANGE (-5800 3875);
DISPLAY INVISIBLE (-5800 3875);
FORCEPROP 2 LAST CDS_LOCATION R1T32
J 0
(-5700 3900);
DISPLAY 0.617021 (-5700 3900);
PAINT AQUA (-5700 3900);
DISPLAY INVISIBLE (-5700 3900);
FORCEPROP 0 LAST ROOM NIC_SPRV
J 0
(-5700 4000);
DISPLAY 1.021277 (-5700 4000);
PAINT ORANGE (-5700 4000);
DISPLAY INVISIBLE (-5700 4000);
FORCEPROP 2 LAST SEC 1
J 0
(-5850 4075);
DISPLAY 0.680851 (-5850 4075);
PAINT MONO (-5850 4075);
DISPLAY INVISIBLE (-5850 4075);
FORCEPROP 2 LAST SEC_TYPE 0603
J 0
(-5850 4075);
DISPLAY 1.021277 (-5850 4075);
PAINT ORANGE (-5850 4075);
DISPLAY INVISIBLE (-5850 4075);
FORCEPROP 0 LAST BOM_COST NT_GBE_BASE
J 0
(-5700 4100);
DISPLAY 1.021277 (-5700 4100);
PAINT ORANGE (-5700 4100);
DISPLAY INVISIBLE (-5700 4100);
FORCEADD RES..1
(-5600 3525);
FORCEPROP 1 LAST PART_NUMBER G22178-002
J 0
(-6025 3550);
DISPLAY 0.617021 (-6025 3550);
PAINT BLUE (-6025 3550);
FORCEPROP 1 LASTPIN (-5700 3525) $PN 1
J 0
(-5688 3537);
DISPLAY 0.617021 (-5688 3537);
PAINT ORANGE (-5688 3537);
FORCEPROP 1 LAST VALUE 0
J 2
(-5650 3475);
DISPLAY 0.617021 (-5650 3475);
PAINT SKYBLUE (-5650 3475);
FORCEPROP 1 LAST LOCATION R1T34
J 0
(-5500 3550);
DISPLAY 0.617021 (-5500 3550);
PAINT AQUA (-5500 3550);
FORCEPROP 1 LAST PACK_TYPE 0603
J 0
(-5525 3475);
DISPLAY 0.617021 (-5525 3475);
PAINT SKYBLUE (-5525 3475);
FORCEPROP 1 LASTPIN (-5500 3525) $PN 2
J 0
(-5538 3537);
DISPLAY 0.617021 (-5538 3537);
PAINT ORANGE (-5538 3537);
FORCEPROP 1 LAST PATH I239
J 0
(-5650 3675);
DISPLAY 0.978723 (-5650 3675);
PAINT WHITE (-5650 3675);
DISPLAY INVISIBLE (-5650 3675);
FORCEPROP 2 LAST SEC 1
J 0
(-5650 3725);
DISPLAY 0.680851 (-5650 3725);
PAINT MONO (-5650 3725);
DISPLAY INVISIBLE (-5650 3725);
FORCEPROP 2 LAST SEC_TYPE 0603
J 0
(-5650 3725);
DISPLAY 1.021277 (-5650 3725);
PAINT ORANGE (-5650 3725);
DISPLAY INVISIBLE (-5650 3725);
FORCEPROP 1 LAST TOLERANCE 5.0%
J 0
(-5600 3425);
DISPLAY 0.617021 (-5600 3425);
PAINT SKYBLUE (-5600 3425);
DISPLAY INVISIBLE (-5600 3425);
FORCEPROP 1 LAST MATERIAL CHIP
J 0
(-5600 3375);
DISPLAY 0.617021 (-5600 3375);
PAINT SKYBLUE (-5600 3375);
DISPLAY INVISIBLE (-5600 3375);
FORCEPROP 1 LAST WATTAGE 1/10W
J 2
(-5625 3375);
DISPLAY 0.617021 (-5625 3375);
PAINT SKYBLUE (-5625 3375);
DISPLAY INVISIBLE (-5625 3375);
FORCEPROP 2 LAST CDS_LIB mstr_discrete
J 0
(-5600 3525);
PAINT ORANGE (-5600 3525);
DISPLAY INVISIBLE (-5600 3525);
FORCEPROP 2 LAST CDS_LOCATION R1T34
J 0
(-5500 3550);
DISPLAY 0.617021 (-5500 3550);
PAINT AQUA (-5500 3550);
DISPLAY INVISIBLE (-5500 3550);
FORCEPROP 0 LAST ROOM NIC_SPRV
J 0
(-5500 3650);
DISPLAY 1.021277 (-5500 3650);
PAINT ORANGE (-5500 3650);
DISPLAY INVISIBLE (-5500 3650);
FORCEPROP 0 LAST BOM_COST NT_GBE_BASE
J 0
(-5500 3750);
DISPLAY 1.021277 (-5500 3750);
PAINT ORANGE (-5500 3750);
DISPLAY INVISIBLE (-5500 3750);
FORCEADD RES..1
(-5800 3725);
FORCEPROP 1 LAST PART_NUMBER G22178-002
J 0
(-6175 3675);
DISPLAY 0.617021 (-6175 3675);
PAINT BLUE (-6175 3675);
FORCEPROP 1 LAST MATERIAL EMPTY
J 0
(-5800 3575);
DISPLAY 0.617021 (-5800 3575);
PAINT RED (-5800 3575);
FORCEPROP 1 LAST VALUE 0
J 2
(-5850 3675);
DISPLAY 0.617021 (-5850 3675);
PAINT SKYBLUE (-5850 3675);
FORCEPROP 1 LASTPIN (-5700 3725) $PN 2
J 0
(-5738 3737);
DISPLAY 0.617021 (-5738 3737);
PAINT ORANGE (-5738 3737);
FORCEPROP 1 LAST PACK_TYPE 0603
J 0
(-5725 3675);
DISPLAY 0.617021 (-5725 3675);
PAINT SKYBLUE (-5725 3675);
FORCEPROP 1 LAST LOCATION R1T33
J 0
(-5700 3750);
DISPLAY 0.617021 (-5700 3750);
PAINT AQUA (-5700 3750);
FORCEPROP 1 LASTPIN (-5900 3725) $PN 1
J 0
(-5888 3737);
DISPLAY 0.617021 (-5888 3737);
PAINT ORANGE (-5888 3737);
FORCEPROP 1 LAST WATTAGE 1/10W
J 2
(-5825 3575);
DISPLAY 0.617021 (-5825 3575);
PAINT SKYBLUE (-5825 3575);
DISPLAY INVISIBLE (-5825 3575);
FORCEPROP 1 LAST TOLERANCE 5.0%
J 0
(-5800 3625);
DISPLAY 0.617021 (-5800 3625);
PAINT SKYBLUE (-5800 3625);
DISPLAY INVISIBLE (-5800 3625);
FORCEPROP 2 LAST CDS_LIB mstr_discrete
J 0
(-5800 3725);
PAINT ORANGE (-5800 3725);
DISPLAY INVISIBLE (-5800 3725);
FORCEPROP 2 LAST CDS_LOCATION R1T33
J 0
(-5700 3750);
DISPLAY 0.617021 (-5700 3750);
PAINT AQUA (-5700 3750);
DISPLAY INVISIBLE (-5700 3750);
FORCEPROP 1 LAST PATH I240
J 0
(-5850 3875);
DISPLAY 0.978723 (-5850 3875);
PAINT WHITE (-5850 3875);
DISPLAY INVISIBLE (-5850 3875);
FORCEPROP 2 LAST SEC 1
J 0
(-5850 3925);
DISPLAY 0.680851 (-5850 3925);
PAINT MONO (-5850 3925);
DISPLAY INVISIBLE (-5850 3925);
FORCEPROP 2 LAST SEC_TYPE 0603
J 0
(-5850 3925);
DISPLAY 1.021277 (-5850 3925);
PAINT ORANGE (-5850 3925);
DISPLAY INVISIBLE (-5850 3925);
FORCEPROP 0 LAST ROOM NIC_SPRV
J 0
(-5700 3850);
DISPLAY 1.021277 (-5700 3850);
PAINT ORANGE (-5700 3850);
DISPLAY INVISIBLE (-5700 3850);
FORCEPROP 0 LAST BOM_COST NT_GBE_BASE
J 0
(-5700 3950);
DISPLAY 1.021277 (-5700 3950);
PAINT ORANGE (-5700 3950);
DISPLAY INVISIBLE (-5700 3950);
FORCEADD CAP_A..1
(-1925 875);
FORCEPROP 1 LASTPIN (-1925 775) $PN 2
J 0
(-1915 755);
DISPLAY 0.617021 (-1915 755);
PAINT ORANGE (-1915 755);
FORCEPROP 1 LAST VOLTAGE 4V
J 0
(-1875 875);
DISPLAY 0.617021 (-1875 875);
PAINT SKYBLUE (-1875 875);
FORCEPROP 1 LASTPIN (-1925 975) $PN 1
J 0
(-1915 955);
DISPLAY 0.617021 (-1915 955);
PAINT ORANGE (-1915 955);
FORCEPROP 1 LAST PACK_TYPE 0603V
J 0
(-1875 675);
DISPLAY 0.617021 (-1875 675);
PAINT SKYBLUE (-1875 675);
FORCEPROP 1 LAST TOLERANCE 20%
J 0
(-1875 825);
DISPLAY 0.617021 (-1875 825);
PAINT SKYBLUE (-1875 825);
FORCEPROP 1 LAST VALUE 22.0UF
J 0
(-1875 925);
DISPLAY 0.617021 (-1875 925);
PAINT SKYBLUE (-1875 925);
FORCEPROP 1 LAST PART_NUMBER E15431-004
J 0
(-1875 725);
DISPLAY 0.617021 (-1875 725);
PAINT BLUE (-1875 725);
FORCEPROP 1 LAST LOCATION C9E12
J 0
(-1875 975);
DISPLAY 0.617021 (-1875 975);
PAINT AQUA (-1875 975);
FORCEPROP 1 LAST MATERIAL EMPTY
J 0
(-1875 775);
DISPLAY 0.617021 (-1875 775);
PAINT RED (-1875 775);
FORCEPROP 2 LAST CDS_LIB dev_discrete
J 0
(-1925 875);
PAINT ORANGE (-1925 875);
DISPLAY INVISIBLE (-1925 875);
FORCEPROP 2 LAST BOM_COST NT_GBE_BASE
J 0
(-1875 1075);
DISPLAY 1.021277 (-1875 1075);
PAINT ORANGE (-1875 1075);
DISPLAY INVISIBLE (-1875 1075);
FORCEPROP 2 LAST SEC 1
J 0
(-1875 1075);
DISPLAY 0.680851 (-1875 1075);
PAINT MONO (-1875 1075);
DISPLAY INVISIBLE (-1875 1075);
FORCEPROP 2 LAST SEC_TYPE 0603V
J 0
(-1875 1075);
DISPLAY 1.021277 (-1875 1075);
PAINT ORANGE (-1875 1075);
DISPLAY INVISIBLE (-1875 1075);
FORCEPROP 1 LAST PATH I241
J 0
(-1875 1025);
DISPLAY 0.978723 (-1875 1025);
PAINT WHITE (-1875 1025);
DISPLAY INVISIBLE (-1875 1025);
FORCEPROP 2 LAST ROOM NIC_SPRV
J 0
(-1875 1025);
DISPLAY 1.021277 (-1875 1025);
PAINT ORANGE (-1875 1025);
DISPLAY INVISIBLE (-1875 1025);
FORCEADD SPRINGVILLE..2
(-4200 3125);
FORCEPROP 2 LASTPIN (-5100 1925) $PN 25
J 2
(-5110 1935);
DISPLAY 0.617021 (-5110 1935);
PAINT ORANGE (-5110 1935);
FORCEPROP 2 LASTPIN (-5100 1975) $PN 26
J 2
(-5110 1985);
DISPLAY 0.617021 (-5110 1985);
PAINT ORANGE (-5110 1985);
FORCEPROP 1 LAST PART_NUMBER G47144-004
J 0
(-5050 1675);
DISPLAY 0.617021 (-5050 1675);
PAINT BLUE (-5050 1675);
FORCEPROP 2 LASTPIN (-5100 3125) $PN 28
J 2
(-5110 3135);
DISPLAY 0.617021 (-5110 3135);
PAINT ORANGE (-5110 3135);
FORCEPROP 2 LASTPIN (-5100 2925) $PN 19
J 2
(-5110 2935);
DISPLAY 0.617021 (-5110 2935);
PAINT ORANGE (-5110 2935);
FORCEPROP 2 LASTPIN (-5100 2825) $PN 29
J 2
(-5110 2835);
DISPLAY 0.617021 (-5110 2835);
PAINT ORANGE (-5110 2835);
FORCEPROP 2 LASTPIN (-5100 2875) $PN 18
J 2
(-5110 2885);
DISPLAY 0.617021 (-5110 2885);
PAINT ORANGE (-5110 2885);
FORCEPROP 2 LASTPIN (-5100 3075) $PN 1
J 2
(-5110 3085);
DISPLAY 0.617021 (-5110 3085);
PAINT ORANGE (-5110 3085);
FORCEPROP 2 LASTPIN (-5100 2625) $PN 43
J 2
(-5110 2635);
DISPLAY 0.617021 (-5110 2635);
PAINT ORANGE (-5110 2635);
FORCEPROP 2 LASTPIN (-5100 2725) $PN 2
J 2
(-5110 2735);
DISPLAY 0.617021 (-5110 2735);
PAINT ORANGE (-5110 2735);
FORCEPROP 2 LASTPIN (-5100 2675) $PN 7
J 2
(-5110 2685);
DISPLAY 0.617021 (-5110 2685);
PAINT ORANGE (-5110 2685);
FORCEPROP 2 LASTPIN (-5100 2475) $PN 9
J 2
(-5110 2485);
DISPLAY 0.617021 (-5110 2485);
PAINT ORANGE (-5110 2485);
FORCEPROP 2 LASTPIN (-5100 2525) $PN 8
J 2
(-5110 2535);
DISPLAY 0.617021 (-5110 2535);
PAINT ORANGE (-5110 2535);
FORCEPROP 2 LASTPIN (-5100 2375) $PN 14
J 2
(-5110 2385);
DISPLAY 0.617021 (-5110 2385);
PAINT ORANGE (-5110 2385);
FORCEPROP 2 LASTPIN (-5100 2075) $PN 23
J 2
(-5110 2085);
DISPLAY 0.617021 (-5110 2085);
PAINT ORANGE (-5110 2085);
FORCEPROP 2 LASTPIN (-5100 2125) $PN 24
J 2
(-5110 2135);
DISPLAY 0.617021 (-5110 2135);
PAINT ORANGE (-5110 2135);
FORCEPROP 2 LASTPIN (-5100 2275) $PN 17
J 2
(-5110 2285);
DISPLAY 0.617021 (-5110 2285);
PAINT ORANGE (-5110 2285);
FORCEPROP 2 LASTPIN (-5100 2225) $PN 16
J 2
(-5110 2235);
DISPLAY 0.617021 (-5110 2235);
PAINT ORANGE (-5110 2235);
FORCEPROP 2 LASTPIN (-5100 3025) $PN 48
J 2
(-5110 3035);
DISPLAY 0.617021 (-5110 3035);
PAINT ORANGE (-5110 3035);
FORCEPROP 2 LASTPIN (-5100 4025) $PN 38
J 2
(-5110 4035);
DISPLAY 0.617021 (-5110 4035);
PAINT ORANGE (-5110 4035);
FORCEPROP 2 LASTPIN (-5100 3875) $PN 56
J 2
(-5110 3885);
DISPLAY 0.617021 (-5110 3885);
PAINT ORANGE (-5110 3885);
FORCEPROP 2 LASTPIN (-5100 3925) $PN 47
J 2
(-5110 3935);
DISPLAY 0.617021 (-5110 3935);
PAINT ORANGE (-5110 3935);
FORCEPROP 2 LASTPIN (-5100 3775) $PN 39
J 2
(-5110 3785);
DISPLAY 0.617021 (-5110 3785);
PAINT ORANGE (-5110 3785);
FORCEPROP 2 LASTPIN (-5100 3475) $PN 64
J 2
(-5110 3485);
DISPLAY 0.617021 (-5110 3485);
PAINT ORANGE (-5110 3485);
FORCEPROP 2 LASTPIN (-5100 3525) $PN 51
J 2
(-5110 3535);
DISPLAY 0.617021 (-5110 3535);
PAINT ORANGE (-5110 3535);
FORCEPROP 2 LASTPIN (-5100 3575) $PN 41
J 2
(-5110 3585);
DISPLAY 0.617021 (-5110 3585);
PAINT ORANGE (-5110 3585);
FORCEPROP 2 LASTPIN (-5100 3625) $PN 27
J 2
(-5110 3635);
DISPLAY 0.617021 (-5110 3635);
PAINT ORANGE (-5110 3635);
FORCEPROP 2 LASTPIN (-5100 3675) $PN 10
J 2
(-5110 3685);
DISPLAY 0.617021 (-5110 3685);
PAINT ORANGE (-5110 3685);
FORCEPROP 2 LASTPIN (-5100 3375) $PN 46
J 2
(-5110 3385);
DISPLAY 0.617021 (-5110 3385);
PAINT ORANGE (-5110 3385);
FORCEPROP 2 LASTPIN (-5100 3225) $PN 45
J 2
(-5110 3235);
DISPLAY 0.617021 (-5110 3235);
PAINT ORANGE (-5110 3235);
FORCEPROP 2 LASTPIN (-5100 4125) $PN 59
J 2
(-5110 4135);
DISPLAY 0.617021 (-5110 4135);
PAINT ORANGE (-5110 4135);
FORCEPROP 2 LASTPIN (-5100 4175) $PN 32
J 2
(-5110 4185);
DISPLAY 0.617021 (-5110 4185);
PAINT ORANGE (-5110 4185);
FORCEPROP 2 LASTPIN (-5100 4225) $PN 11
J 2
(-5110 4235);
DISPLAY 0.617021 (-5110 4235);
PAINT ORANGE (-5110 4235);
FORCEPROP 2 LASTPIN (-5100 4275) $PN 42
J 2
(-5110 4285);
DISPLAY 0.617021 (-5110 4285);
PAINT ORANGE (-5110 4285);
FORCEPROP 1 LAST LOCATION EU9E1
J 0
(-5050 4525);
DISPLAY 0.617021 (-5050 4525);
PAINT AQUA (-5050 4525);
FORCEPROP 1 LAST MATERIAL IC
J 0
(-5050 4475);
DISPLAY 0.617021 (-5050 4475);
PAINT SKYBLUE (-5050 4475);
FORCEPROP 2 LASTPIN (-3300 1875) $PN 65
J 0
(-3290 1885);
DISPLAY 0.617021 (-3290 1885);
PAINT ORANGE (-3290 1885);
FORCEPROP 2 LASTPIN (-3300 1975) $PN 22
J 0
(-3290 1985);
DISPLAY 0.617021 (-3290 1985);
PAINT ORANGE (-3290 1985);
FORCEPROP 2 LASTPIN (-3300 2125) $PN 21
J 0
(-3290 2135);
DISPLAY 0.617021 (-3290 2135);
PAINT ORANGE (-3290 2135);
FORCEPROP 2 LASTPIN (-3300 2075) $PN 20
J 0
(-3290 2085);
DISPLAY 0.617021 (-3290 2085);
PAINT ORANGE (-3290 2085);
FORCEPROP 2 LASTPIN (-3300 2275) $PN 13
J 0
(-3290 2285);
DISPLAY 0.617021 (-3290 2285);
PAINT ORANGE (-3290 2285);
FORCEPROP 2 LASTPIN (-3300 2375) $PN 12
J 0
(-3290 2385);
DISPLAY 0.617021 (-3290 2385);
PAINT ORANGE (-3290 2385);
FORCEPROP 2 LASTPIN (-3300 2325) $PN 15
J 0
(-3290 2335);
DISPLAY 0.617021 (-3290 2335);
PAINT ORANGE (-3290 2335);
FORCEPROP 2 LASTPIN (-3300 2475) $PN 6
J 0
(-3290 2485);
DISPLAY 0.617021 (-3290 2485);
PAINT ORANGE (-3290 2485);
FORCEPROP 2 LASTPIN (-3300 2525) $PN 5
J 0
(-3290 2535);
DISPLAY 0.617021 (-3290 2535);
PAINT ORANGE (-3290 2535);
FORCEPROP 2 LASTPIN (-3300 2675) $PN 3
J 0
(-3290 2685);
DISPLAY 0.617021 (-3290 2685);
PAINT ORANGE (-3290 2685);
FORCEPROP 2 LASTPIN (-3300 2725) $PN 44
J 0
(-3290 2735);
DISPLAY 0.617021 (-3290 2735);
PAINT ORANGE (-3290 2735);
FORCEPROP 2 LASTPIN (-3300 2975) $PN 36
J 0
(-3290 2985);
DISPLAY 0.617021 (-3290 2985);
PAINT ORANGE (-3290 2985);
FORCEPROP 2 LASTPIN (-3300 3025) $PN 34
J 0
(-3290 3035);
DISPLAY 0.617021 (-3290 3035);
PAINT ORANGE (-3290 3035);
FORCEPROP 2 LASTPIN (-3300 2925) $PN 35
J 0
(-3290 2935);
DISPLAY 0.617021 (-3290 2935);
PAINT ORANGE (-3290 2935);
FORCEPROP 2 LASTPIN (-3300 2825) $PN 4
J 0
(-3290 2835);
DISPLAY 0.617021 (-3290 2835);
PAINT ORANGE (-3290 2835);
FORCEPROP 2 LASTPIN (-3300 3275) $PN 60
J 0
(-3290 3285);
DISPLAY 0.617021 (-3290 3285);
PAINT ORANGE (-3290 3285);
FORCEPROP 2 LASTPIN (-3300 3225) $PN 62
J 0
(-3290 3235);
DISPLAY 0.617021 (-3290 3235);
PAINT ORANGE (-3290 3235);
FORCEPROP 2 LASTPIN (-3300 3175) $PN 61
J 0
(-3290 3185);
DISPLAY 0.617021 (-3290 3185);
PAINT ORANGE (-3290 3185);
FORCEPROP 2 LASTPIN (-3300 3125) $PN 63
J 0
(-3290 3135);
DISPLAY 0.617021 (-3290 3135);
PAINT ORANGE (-3290 3135);
FORCEPROP 2 LASTPIN (-3300 3375) $PN 37
J 0
(-3290 3385);
DISPLAY 0.617021 (-3290 3385);
PAINT ORANGE (-3290 3385);
FORCEPROP 2 LASTPIN (-3300 3775) $PN 30
J 0
(-3290 3785);
DISPLAY 0.617021 (-3290 3785);
PAINT ORANGE (-3290 3785);
FORCEPROP 2 LASTPIN (-3300 3725) $PN 31
J 0
(-3290 3735);
DISPLAY 0.617021 (-3290 3735);
PAINT ORANGE (-3290 3735);
FORCEPROP 2 LASTPIN (-3300 3625) $PN 40
J 0
(-3290 3635);
DISPLAY 0.617021 (-3290 3635);
PAINT ORANGE (-3290 3635);
FORCEPROP 2 LASTPIN (-3300 3825) $PN 33
J 0
(-3290 3835);
DISPLAY 0.617021 (-3290 3835);
PAINT ORANGE (-3290 3835);
FORCEPROP 2 LASTPIN (-3300 3975) $PN 58
J 0
(-3290 3985);
DISPLAY 0.617021 (-3290 3985);
PAINT ORANGE (-3290 3985);
FORCEPROP 2 LASTPIN (-3300 4025) $PN 54
J 0
(-3290 4035);
DISPLAY 0.617021 (-3290 4035);
PAINT ORANGE (-3290 4035);
FORCEPROP 2 LASTPIN (-3300 3925) $PN 57
J 0
(-3290 3935);
DISPLAY 0.617021 (-3290 3935);
PAINT ORANGE (-3290 3935);
FORCEPROP 2 LASTPIN (-3300 4075) $PN 55
J 0
(-3290 4085);
DISPLAY 0.617021 (-3290 4085);
PAINT ORANGE (-3290 4085);
FORCEPROP 2 LASTPIN (-3300 4125) $PN 52
J 0
(-3290 4135);
DISPLAY 0.617021 (-3290 4135);
PAINT ORANGE (-3290 4135);
FORCEPROP 2 LASTPIN (-3300 4225) $PN 49
J 0
(-3290 4235);
DISPLAY 0.617021 (-3290 4235);
PAINT ORANGE (-3290 4235);
FORCEPROP 2 LASTPIN (-3300 4175) $PN 53
J 0
(-3290 4185);
DISPLAY 0.617021 (-3290 4185);
PAINT ORANGE (-3290 4185);
FORCEPROP 2 LASTPIN (-3300 4275) $PN 50
J 0
(-3290 4285);
DISPLAY 0.617021 (-3290 4285);
PAINT ORANGE (-3290 4285);
FORCEPROP 2 LAST CDS_LIB mstr_intel
J 0
(-4200 3125);
PAINT ORANGE (-4200 3125);
DISPLAY INVISIBLE (-4200 3125);
FORCEPROP 2 LAST SEC 1
J 0
(-5050 4575);
DISPLAY 0.680851 (-5050 4575);
PAINT MONO (-5050 4575);
DISPLAY INVISIBLE (-5050 4575);
FORCEPROP 2 LAST CDS_LOCATION EU9E1
J 0
(-5050 4525);
DISPLAY 0.617021 (-5050 4525);
PAINT AQUA (-5050 4525);
DISPLAY INVISIBLE (-5050 4525);
FORCEPROP 1 LAST PACK_TYPE SM1
J 0
(-5050 4575);
PAINT SKYBLUE (-5050 4575);
DISPLAY INVISIBLE (-5050 4575);
FORCEPROP 2 LAST SEC_TYPE SM1
J 0
(-5050 4575);
DISPLAY 1.021277 (-5050 4575);
PAINT ORANGE (-5050 4575);
DISPLAY INVISIBLE (-5050 4575);
FORCEPROP 2 LAST ROOM NIC_SPRV
J 0
(-5050 4575);
DISPLAY 1.021277 (-5050 4575);
PAINT ORANGE (-5050 4575);
DISPLAY INVISIBLE (-5050 4575);
FORCEPROP 2 LAST BOM_COST NT_GBE_BASE
J 0
(-5050 4625);
DISPLAY 1.021277 (-5050 4625);
PAINT ORANGE (-5050 4625);
DISPLAY INVISIBLE (-5050 4625);
FORCEPROP 1 LAST PATH I72
J 0
(-4200 4475);
PAINT GREEN (-4200 4475);
DISPLAY INVISIBLE (-4200 4475);
FORCEADD P0V9_LAN..1
(-5725 4525);
FORCEPROP 3 LASTPIN (-5725 4475) SIG_NAME P0V9_LAN\g
J 0
(-5715 4485);
DISPLAY 0.659574 (-5715 4485);
PAINT MONO (-5715 4485);
DISPLAY INVISIBLE (-5715 4485);
FORCEPROP 1 LAST BODY_TYPE PLUMBING
J 0
(-5770 4482);
DISPLAY 0.340426 (-5770 4482);
PAINT GREEN (-5770 4482);
DISPLAY INVISIBLE (-5770 4482);
FORCEPROP 1 LAST VOLTAGE 0.9V
J 0
(-5770 4482);
DISPLAY 0.340426 (-5770 4482);
PAINT SKYBLUE (-5770 4482);
DISPLAY INVISIBLE (-5770 4482);
FORCEPROP 2 LAST CDS_LIB mstr_symbols
J 0
(-5725 4525);
PAINT ORANGE (-5725 4525);
DISPLAY INVISIBLE (-5725 4525);
FORCEPROP 1 LAST PATH I73
J 0
(-5675 4550);
DISPLAY 0.872340 (-5675 4550);
PAINT AQUA (-5675 4550);
DISPLAY INVISIBLE (-5675 4550);
FORCEPROP 1 LAST HDL_POWER P0V9_LAN
J 1
(-5725 4575);
DISPLAY 0.872340 (-5725 4575);
PAINT GREEN (-5725 4575);
DISPLAY INVISIBLE (-5725 4575);
FORCEADD P1V5_LAN..1
(-6325 4300);
FORCEPROP 3 LASTPIN (-6325 4250) SIG_NAME P1V5_LAN\g
J 0
(-6315 4260);
DISPLAY 0.659574 (-6315 4260);
PAINT MONO (-6315 4260);
DISPLAY INVISIBLE (-6315 4260);
FORCEPROP 1 LAST VOLTAGE 1.5V
J 0
(-6370 4257);
DISPLAY 0.340426 (-6370 4257);
PAINT SKYBLUE (-6370 4257);
DISPLAY INVISIBLE (-6370 4257);
FORCEPROP 2 LAST CDS_LIB mstr_symbols
J 0
(-6325 4300);
PAINT ORANGE (-6325 4300);
DISPLAY INVISIBLE (-6325 4300);
FORCEPROP 1 LAST BODY_TYPE PLUMBING
J 0
(-6370 4257);
DISPLAY 0.340426 (-6370 4257);
PAINT GREEN (-6370 4257);
DISPLAY INVISIBLE (-6370 4257);
FORCEPROP 1 LAST PATH I74
J 0
(-6275 4325);
DISPLAY 0.872340 (-6275 4325);
PAINT AQUA (-6275 4325);
DISPLAY INVISIBLE (-6275 4325);
FORCEPROP 1 LAST HDL_POWER P1V5_LAN
J 1
(-6325 4350);
DISPLAY 0.872340 (-6325 4350);
PAINT GREEN (-6325 4350);
DISPLAY INVISIBLE (-6325 4350);
FORCEADD CAP..1
(-2725 3500);
FORCEPROP 1 LAST PART_NUMBER A36096-063
J 0
(-2975 3450);
DISPLAY 0.617021 (-2975 3450);
PAINT BLUE (-2975 3450);
FORCEPROP 1 LAST PACK_TYPE 0402LF
J 0
(-2925 3400);
DISPLAY 0.617021 (-2925 3400);
PAINT SKYBLUE (-2925 3400);
FORCEPROP 1 LAST TOLERANCE 10%
J 0
(-2675 3450);
DISPLAY 0.617021 (-2675 3450);
PAINT SKYBLUE (-2675 3450);
FORCEPROP 1 LAST VOLTAGE 25V
J 0
(-2675 3500);
DISPLAY 0.617021 (-2675 3500);
PAINT SKYBLUE (-2675 3500);
FORCEPROP 1 LAST MATERIAL X7R
J 0
(-2675 3400);
DISPLAY 0.617021 (-2675 3400);
PAINT SKYBLUE (-2675 3400);
FORCEPROP 1 LASTPIN (-2725 3400) $PN 2
J 0
(-2715 3380);
DISPLAY 0.617021 (-2715 3380);
PAINT ORANGE (-2715 3380);
FORCEPROP 1 LASTPIN (-2725 3600) $PN 1
J 0
(-2715 3580);
DISPLAY 0.617021 (-2715 3580);
PAINT ORANGE (-2715 3580);
FORCEPROP 1 LAST VALUE 0.039UF
J 0
(-2675 3550);
DISPLAY 0.617021 (-2675 3550);
PAINT SKYBLUE (-2675 3550);
FORCEPROP 1 LAST LOCATION C9E7
J 0
(-2675 3600);
DISPLAY 0.617021 (-2675 3600);
PAINT AQUA (-2675 3600);
FORCEPROP 2 LAST CDS_LIB mstr_discrete
J 0
(-2725 3500);
PAINT ORANGE (-2725 3500);
DISPLAY INVISIBLE (-2725 3500);
FORCEPROP 2 LAST ROOM NIC_SPRV
J 0
(-2675 3650);
DISPLAY 1.021277 (-2675 3650);
PAINT ORANGE (-2675 3650);
DISPLAY INVISIBLE (-2675 3650);
FORCEPROP 1 LAST PATH I76
J 0
(-2675 3650);
DISPLAY 0.978723 (-2675 3650);
PAINT WHITE (-2675 3650);
DISPLAY INVISIBLE (-2675 3650);
FORCEPROP 2 LAST CDS_LOCATION C9E7
J 0
(-2675 3600);
DISPLAY 0.617021 (-2675 3600);
PAINT AQUA (-2675 3600);
DISPLAY INVISIBLE (-2675 3600);
FORCEPROP 2 LAST SEC 1
J 0
(-2675 3700);
PAINT MONO (-2675 3700);
DISPLAY INVISIBLE (-2675 3700);
FORCEPROP 2 LAST BOM_COST NT_GBE_BASE
J 0
(-2675 3700);
DISPLAY 1.021277 (-2675 3700);
PAINT ORANGE (-2675 3700);
DISPLAY INVISIBLE (-2675 3700);
FORCEPROP 2 LAST SEC_TYPE 0402LF
J 0
(-2675 3700);
DISPLAY 1.021277 (-2675 3700);
PAINT ORANGE (-2675 3700);
DISPLAY INVISIBLE (-2675 3700);
FORCEADD GND..1
(-3175 1425);
FORCEPROP 3 LASTPIN (-3175 1475) SIG_NAME GND\g
J 0
(-3165 1485);
DISPLAY 0.659574 (-3165 1485);
PAINT MONO (-3165 1485);
DISPLAY INVISIBLE (-3165 1485);
FORCEPROP 1 LAST VOLTAGE 0.0V
J 0
(-3220 1382);
DISPLAY 0.340426 (-3220 1382);
PAINT SKYBLUE (-3220 1382);
DISPLAY INVISIBLE (-3220 1382);
FORCEPROP 1 LAST PATH I77
J 0
(-3100 1425);
DISPLAY 0.872340 (-3100 1425);
PAINT AQUA (-3100 1425);
DISPLAY INVISIBLE (-3100 1425);
FORCEPROP 1 LAST BODY_TYPE PLUMBING
J 0
(-3220 1382);
DISPLAY 0.340426 (-3220 1382);
PAINT GREEN (-3220 1382);
DISPLAY INVISIBLE (-3220 1382);
FORCEPROP 2 LAST CDS_LIB mstr_symbols
J 0
(-3175 1425);
PAINT ORANGE (-3175 1425);
DISPLAY INVISIBLE (-3175 1425);
FORCEPROP 1 LAST SIZE 1B
J 0
(-3100 1375);
DISPLAY 0.872340 (-3100 1375);
PAINT AQUA (-3100 1375);
DISPLAY INVISIBLE (-3100 1375);
FORCEPROP 1 LAST HDL_POWER GND
J 0
(-3175 1575);
DISPLAY 0.872340 (-3175 1575);
PAINT GREEN (-3175 1575);
DISPLAY INVISIBLE (-3175 1575);
FORCEADD OFFPAGE..1
(-6050 2675);
FORCEPROP 2 LAST $XR0 139 
J 0
(-6302 2675);
DISPLAY 0.638298 (-6302 2675);
PAINT MONO (-6302 2675);
FORCEPROP 2 LAST $XR1 147 
J 0
(-6422 2675);
DISPLAY 0.638298 (-6422 2675);
PAINT MONO (-6422 2675);
FORCEPROP 2 LAST $XR2 151 
J 0
(-6542 2675);
DISPLAY 0.638298 (-6542 2675);
PAINT MONO (-6542 2675);
FORCEPROP 2 LAST $XR3 121 
J 0
(-6542 2675);
DISPLAY 0.638298 (-6542 2675);
PAINT MONO (-6542 2675);
FORCEPROP 1 LAST OFFPAGE TRUE
J 0
(-5725 2550);
DISPLAY 0.872340 (-5725 2550);
PAINT GREEN (-5725 2550);
DISPLAY INVISIBLE (-5725 2550);
FORCEPROP 2 LAST CDS_LIB mstr_standard
J 0
(-6050 2675);
PAINT ORANGE (-6050 2675);
DISPLAY INVISIBLE (-6050 2675);
FORCEPROP 1 LAST COMMENT_BODY TRUE
J 0
(-5925 2575);
DISPLAY 0.872340 (-5925 2575);
PAINT GREEN (-5925 2575);
DISPLAY INVISIBLE (-5925 2575);
FORCEPROP 2 LAST PATH I84
J 0
(-6000 2750);
DISPLAY 1.021277 (-6000 2750);
PAINT ORANGE (-6000 2750);
DISPLAY INVISIBLE (-6000 2750);
FORCEADD OFFPAGE..3
(-900 2125);
FORCEPROP 2 LAST $XR0 116 
J 0
(-686 2125);
DISPLAY 0.638298 (-686 2125);
PAINT MONO (-686 2125);
FORCEPROP 1 LAST OFFPAGE TRUE
J 0
(-575 2000);
DISPLAY 0.872340 (-575 2000);
PAINT GREEN (-575 2000);
DISPLAY INVISIBLE (-575 2000);
FORCEPROP 1 LAST COMMENT_BODY TRUE
J 0
(-950 2025);
DISPLAY 0.872340 (-950 2025);
PAINT GREEN (-950 2025);
DISPLAY INVISIBLE (-950 2025);
FORCEPROP 2 LAST CDS_LIB mstr_standard
J 0
(-900 2125);
PAINT ORANGE (-900 2125);
DISPLAY INVISIBLE (-900 2125);
FORCEPROP 2 LAST PATH I85
J 0
(-700 2200);
DISPLAY 1.021277 (-700 2200);
PAINT ORANGE (-700 2200);
DISPLAY INVISIBLE (-700 2200);
FORCEADD OFFPAGE..3
(-900 2075);
FORCEPROP 2 LAST $XR0 116 
J 0
(-686 2075);
DISPLAY 0.638298 (-686 2075);
PAINT MONO (-686 2075);
FORCEPROP 1 LAST COMMENT_BODY TRUE
J 0
(-950 1975);
DISPLAY 0.872340 (-950 1975);
PAINT GREEN (-950 1975);
DISPLAY INVISIBLE (-950 1975);
FORCEPROP 1 LAST OFFPAGE TRUE
J 0
(-575 1950);
DISPLAY 0.872340 (-575 1950);
PAINT GREEN (-575 1950);
DISPLAY INVISIBLE (-575 1950);
FORCEPROP 2 LAST CDS_LIB mstr_standard
J 0
(-900 2075);
PAINT ORANGE (-900 2075);
DISPLAY INVISIBLE (-900 2075);
FORCEPROP 2 LAST PATH I86
J 0
(-700 2150);
DISPLAY 1.021277 (-700 2150);
PAINT ORANGE (-700 2150);
DISPLAY INVISIBLE (-700 2150);
FORCEADD CAP_A..2
(-1650 2075);
FORCEPROP 1 LAST VALUE 0.1UF
J 2
(-1650 1975);
DISPLAY 0.617021 (-1650 1975);
PAINT SKYBLUE (-1650 1975);
FORCEPROP 1 LAST TOLERANCE 10%
J 2
(-1650 1925);
DISPLAY 0.617021 (-1650 1925);
PAINT SKYBLUE (-1650 1925);
FORCEPROP 1 LAST PACK_TYPE 0402V
J 1
(-1650 1875);
DISPLAY 0.617021 (-1650 1875);
PAINT SKYBLUE (-1650 1875);
FORCEPROP 1 LAST VOLTAGE 16V
J 0
(-1650 1975);
DISPLAY 0.617021 (-1650 1975);
PAINT SKYBLUE (-1650 1975);
FORCEPROP 1 LAST MATERIAL X7R
J 0
(-1650 1925);
DISPLAY 0.617021 (-1650 1925);
PAINT SKYBLUE (-1650 1925);
FORCEPROP 1 LASTPIN (-1750 2075) $PN 1
J 0
(-1760 2090);
DISPLAY 0.617021 (-1760 2090);
PAINT ORANGE (-1760 2090);
FORCEPROP 1 LASTPIN (-1550 2075) $PN 2
J 0
(-1565 2090);
DISPLAY 0.617021 (-1565 2090);
PAINT ORANGE (-1565 2090);
FORCEPROP 1 LAST PART_NUMBER A36096-030
J 1
(-1650 2125);
DISPLAY 0.617021 (-1650 2125);
PAINT BLUE (-1650 2125);
FORCEPROP 1 LAST LOCATION C9E5
J 1
(-1450 2075);
DISPLAY 0.617021 (-1450 2075);
PAINT AQUA (-1450 2075);
FORCEPROP 2 LAST CDS_LIB dev_discrete
J 0
(-1650 2075);
PAINT ORANGE (-1650 2075);
DISPLAY INVISIBLE (-1650 2075);
FORCEPROP 2 LAST ROOM NIC_SPRV
J 0
(-1650 2250);
DISPLAY 1.021277 (-1650 2250);
PAINT ORANGE (-1650 2250);
DISPLAY INVISIBLE (-1650 2250);
FORCEPROP 2 LAST BOM_COST NT_GBE_BASE
J 0
(-1650 2300);
DISPLAY 1.021277 (-1650 2300);
PAINT ORANGE (-1650 2300);
DISPLAY INVISIBLE (-1650 2300);
FORCEPROP 1 LAST PATH I87
J 0
(-1650 2275);
DISPLAY 0.978723 (-1650 2275);
PAINT WHITE (-1650 2275);
DISPLAY INVISIBLE (-1650 2275);
FORCEPROP 2 LAST SEC 1
J 0
(-1650 2325);
DISPLAY 0.680851 (-1650 2325);
PAINT MONO (-1650 2325);
DISPLAY INVISIBLE (-1650 2325);
FORCEPROP 2 LAST SEC_TYPE 0402V
J 0
(-1650 2325);
DISPLAY 1.021277 (-1650 2325);
PAINT ORANGE (-1650 2325);
DISPLAY INVISIBLE (-1650 2325);
FORCEPROP 2 LAST CDS_SEC 1
J 0
(-1450 2125);
PAINT ORANGE (-1450 2125);
DISPLAY INVISIBLE (-1450 2125);
FORCEPROP 2 LAST CDS_LOCATION C9E5
J 1
(-1450 2075);
DISPLAY 0.617021 (-1450 2075);
PAINT AQUA (-1450 2075);
DISPLAY INVISIBLE (-1450 2075);
FORCEADD CAP_A..2
(-2400 2125);
FORCEPROP 1 LAST MATERIAL X7R
J 0
(-2400 1975);
DISPLAY 0.617021 (-2400 1975);
PAINT SKYBLUE (-2400 1975);
FORCEPROP 1 LAST PACK_TYPE 0402V
J 1
(-2400 1925);
DISPLAY 0.617021 (-2400 1925);
PAINT SKYBLUE (-2400 1925);
FORCEPROP 1 LAST TOLERANCE 10%
J 2
(-2400 1975);
DISPLAY 0.617021 (-2400 1975);
PAINT SKYBLUE (-2400 1975);
FORCEPROP 1 LAST VOLTAGE 16V
J 0
(-2400 2025);
DISPLAY 0.617021 (-2400 2025);
PAINT SKYBLUE (-2400 2025);
FORCEPROP 1 LAST VALUE 0.1UF
J 2
(-2400 2025);
DISPLAY 0.617021 (-2400 2025);
PAINT SKYBLUE (-2400 2025);
FORCEPROP 1 LASTPIN (-2500 2125) $PN 1
J 0
(-2510 2140);
DISPLAY 0.617021 (-2510 2140);
PAINT ORANGE (-2510 2140);
FORCEPROP 1 LASTPIN (-2300 2125) $PN 2
J 0
(-2315 2140);
DISPLAY 0.617021 (-2315 2140);
PAINT ORANGE (-2315 2140);
FORCEPROP 1 LAST PART_NUMBER A36096-030
J 1
(-2400 2175);
DISPLAY 0.617021 (-2400 2175);
PAINT BLUE (-2400 2175);
FORCEPROP 1 LAST LOCATION C9E4
J 1
(-2200 2125);
DISPLAY 0.617021 (-2200 2125);
PAINT AQUA (-2200 2125);
FORCEPROP 2 LAST CDS_LIB dev_discrete
J 0
(-2400 2125);
PAINT ORANGE (-2400 2125);
DISPLAY INVISIBLE (-2400 2125);
FORCEPROP 2 LAST ROOM NIC_SPRV
J 0
(-2400 2275);
DISPLAY 1.021277 (-2400 2275);
PAINT ORANGE (-2400 2275);
DISPLAY INVISIBLE (-2400 2275);
FORCEPROP 1 LAST PATH I88
J 0
(-2400 2325);
DISPLAY 0.978723 (-2400 2325);
PAINT WHITE (-2400 2325);
DISPLAY INVISIBLE (-2400 2325);
FORCEPROP 2 LAST BOM_COST NT_GBE_BASE
J 0
(-2400 2325);
DISPLAY 1.021277 (-2400 2325);
PAINT ORANGE (-2400 2325);
DISPLAY INVISIBLE (-2400 2325);
FORCEPROP 2 LAST SEC 1
J 0
(-2400 2375);
DISPLAY 0.680851 (-2400 2375);
PAINT MONO (-2400 2375);
DISPLAY INVISIBLE (-2400 2375);
FORCEPROP 2 LAST SEC_TYPE 0402V
J 0
(-2400 2375);
DISPLAY 1.021277 (-2400 2375);
PAINT ORANGE (-2400 2375);
DISPLAY INVISIBLE (-2400 2375);
FORCEPROP 2 LAST CDS_LOCATION C9E4
J 1
(-2200 2125);
DISPLAY 0.617021 (-2200 2125);
PAINT AQUA (-2200 2125);
DISPLAY INVISIBLE (-2200 2125);
FORCEPROP 2 LAST CDS_SEC 1
J 0
(-2200 2175);
PAINT ORANGE (-2200 2175);
DISPLAY INVISIBLE (-2200 2175);
FORCEADD CAP_A..2
(-5775 2125);
FORCEPROP 1 LAST TOLERANCE 10%
J 2
(-5775 1975);
DISPLAY 0.617021 (-5775 1975);
PAINT SKYBLUE (-5775 1975);
FORCEPROP 1 LAST PACK_TYPE 0402V
J 1
(-5775 1925);
DISPLAY 0.617021 (-5775 1925);
PAINT SKYBLUE (-5775 1925);
FORCEPROP 1 LAST MATERIAL X7R
J 0
(-5775 1975);
DISPLAY 0.617021 (-5775 1975);
PAINT SKYBLUE (-5775 1975);
FORCEPROP 1 LAST VOLTAGE 16V
J 0
(-5775 2025);
DISPLAY 0.617021 (-5775 2025);
PAINT SKYBLUE (-5775 2025);
FORCEPROP 1 LAST VALUE 0.1UF
J 2
(-5775 2025);
DISPLAY 0.617021 (-5775 2025);
PAINT SKYBLUE (-5775 2025);
FORCEPROP 1 LASTPIN (-5675 2125) $PN 2
J 0
(-5690 2140);
DISPLAY 0.617021 (-5690 2140);
PAINT ORANGE (-5690 2140);
FORCEPROP 1 LASTPIN (-5875 2125) $PN 1
J 0
(-5885 2140);
DISPLAY 0.617021 (-5885 2140);
PAINT ORANGE (-5885 2140);
FORCEPROP 1 LAST LOCATION C2M23
J 1
(-5750 2225);
DISPLAY 0.617021 (-5750 2225);
PAINT AQUA (-5750 2225);
FORCEPROP 1 LAST PART_NUMBER A36096-030
J 1
(-5775 2175);
DISPLAY 0.617021 (-5775 2175);
PAINT BLUE (-5775 2175);
FORCEPROP 2 LAST CDS_LOCATION C2M23
J 1
(-5750 2225);
DISPLAY 0.617021 (-5750 2225);
PAINT AQUA (-5750 2225);
DISPLAY INVISIBLE (-5750 2225);
FORCEPROP 2 LAST CDS_LIB dev_discrete
J 0
(-5775 2125);
PAINT ORANGE (-5775 2125);
DISPLAY INVISIBLE (-5775 2125);
FORCEPROP 2 LAST CDS_SEC 1
J 0
(-5750 2275);
PAINT ORANGE (-5750 2275);
DISPLAY INVISIBLE (-5750 2275);
FORCEPROP 2 LAST ROOM NIC_SPRV
J 0
(-5750 2275);
DISPLAY 1.021277 (-5750 2275);
PAINT ORANGE (-5750 2275);
DISPLAY INVISIBLE (-5750 2275);
FORCEPROP 2 LAST BOM_COST NT_GBE_BASE
J 0
(-5750 2325);
DISPLAY 1.021277 (-5750 2325);
PAINT ORANGE (-5750 2325);
DISPLAY INVISIBLE (-5750 2325);
FORCEPROP 1 LAST PATH I89
J 0
(-5775 2325);
DISPLAY 0.978723 (-5775 2325);
PAINT WHITE (-5775 2325);
DISPLAY INVISIBLE (-5775 2325);
FORCEPROP 2 LAST SEC_TYPE 0402V
J 0
(-5775 2375);
DISPLAY 1.021277 (-5775 2375);
PAINT ORANGE (-5775 2375);
DISPLAY INVISIBLE (-5775 2375);
FORCEPROP 2 LAST SEC 1
J 0
(-5775 2375);
DISPLAY 0.680851 (-5775 2375);
PAINT MONO (-5775 2375);
DISPLAY INVISIBLE (-5775 2375);
FORCEADD CAP_A..2
(-6000 2075);
FORCEPROP 1 LAST VALUE 0.1UF
J 2
(-6000 1975);
DISPLAY 0.617021 (-6000 1975);
PAINT SKYBLUE (-6000 1975);
FORCEPROP 1 LAST PART_NUMBER A36096-030
J 1
(-6000 2125);
DISPLAY 0.617021 (-6000 2125);
PAINT BLUE (-6000 2125);
FORCEPROP 1 LAST TOLERANCE 10%
J 2
(-6000 1925);
DISPLAY 0.617021 (-6000 1925);
PAINT SKYBLUE (-6000 1925);
FORCEPROP 1 LAST PACK_TYPE 0402V
J 1
(-6000 1875);
DISPLAY 0.617021 (-6000 1875);
PAINT SKYBLUE (-6000 1875);
FORCEPROP 1 LAST MATERIAL X7R
J 0
(-6000 1925);
DISPLAY 0.617021 (-6000 1925);
PAINT SKYBLUE (-6000 1925);
FORCEPROP 1 LAST VOLTAGE 16V
J 0
(-6000 1975);
DISPLAY 0.617021 (-6000 1975);
PAINT SKYBLUE (-6000 1975);
FORCEPROP 1 LAST LOCATION C2M24
J 1
(-6000 2175);
DISPLAY 0.617021 (-6000 2175);
PAINT AQUA (-6000 2175);
FORCEPROP 1 LASTPIN (-6100 2075) $PN 1
J 0
(-6110 2090);
DISPLAY 0.617021 (-6110 2090);
PAINT ORANGE (-6110 2090);
FORCEPROP 1 LASTPIN (-5900 2075) $PN 2
J 0
(-5915 2090);
DISPLAY 0.617021 (-5915 2090);
PAINT ORANGE (-5915 2090);
FORCEPROP 2 LAST ROOM NIC_SPRV
J 0
(-6000 2225);
DISPLAY 1.021277 (-6000 2225);
PAINT ORANGE (-6000 2225);
DISPLAY INVISIBLE (-6000 2225);
FORCEPROP 2 LAST CDS_LOCATION C2M24
J 1
(-6000 2175);
DISPLAY 0.617021 (-6000 2175);
PAINT AQUA (-6000 2175);
DISPLAY INVISIBLE (-6000 2175);
FORCEPROP 2 LAST CDS_LIB dev_discrete
J 0
(-6000 2075);
PAINT ORANGE (-6000 2075);
DISPLAY INVISIBLE (-6000 2075);
FORCEPROP 2 LAST CDS_SEC 1
J 0
(-6000 2225);
PAINT ORANGE (-6000 2225);
DISPLAY INVISIBLE (-6000 2225);
FORCEPROP 1 LAST PATH I90
J 0
(-6000 2275);
DISPLAY 0.978723 (-6000 2275);
PAINT WHITE (-6000 2275);
DISPLAY INVISIBLE (-6000 2275);
FORCEPROP 2 LAST BOM_COST NT_GBE_BASE
J 0
(-6000 2275);
DISPLAY 1.021277 (-6000 2275);
PAINT ORANGE (-6000 2275);
DISPLAY INVISIBLE (-6000 2275);
FORCEPROP 2 LAST SEC 1
J 0
(-6000 2325);
DISPLAY 0.680851 (-6000 2325);
PAINT MONO (-6000 2325);
DISPLAY INVISIBLE (-6000 2325);
FORCEPROP 2 LAST SEC_TYPE 0402V
J 0
(-6000 2325);
DISPLAY 1.021277 (-6000 2325);
PAINT ORANGE (-6000 2325);
DISPLAY INVISIBLE (-6000 2325);
FORCEADD OFFPAGE..6
(-6750 2075);
FORCEPROP 2 LAST $XR0 116 
J 0
(-7030 2075);
DISPLAY 0.638298 (-7030 2075);
PAINT MONO (-7030 2075);
FORCEPROP 1 LAST OFFPAGE TRUE
J 0
(-6425 1950);
DISPLAY 0.872340 (-6425 1950);
PAINT GREEN (-6425 1950);
DISPLAY INVISIBLE (-6425 1950);
FORCEPROP 1 LAST COMMENT_BODY TRUE
J 0
(-6650 2000);
DISPLAY 0.872340 (-6650 2000);
PAINT GREEN (-6650 2000);
DISPLAY INVISIBLE (-6650 2000);
FORCEPROP 2 LAST CDS_LIB mstr_standard
J 0
(-6750 2075);
PAINT ORANGE (-6750 2075);
DISPLAY INVISIBLE (-6750 2075);
FORCEPROP 2 LAST PATH I91
J 0
(-6700 2150);
DISPLAY 1.021277 (-6700 2150);
PAINT ORANGE (-6700 2150);
DISPLAY INVISIBLE (-6700 2150);
FORCEADD OFFPAGE..6
(-6750 2125);
FORCEPROP 2 LAST $XR0 116 
J 0
(-7030 2125);
DISPLAY 0.638298 (-7030 2125);
PAINT MONO (-7030 2125);
FORCEPROP 1 LAST OFFPAGE TRUE
J 0
(-6425 2000);
DISPLAY 0.872340 (-6425 2000);
PAINT GREEN (-6425 2000);
DISPLAY INVISIBLE (-6425 2000);
FORCEPROP 2 LAST CDS_LIB mstr_standard
J 0
(-6750 2125);
PAINT ORANGE (-6750 2125);
DISPLAY INVISIBLE (-6750 2125);
FORCEPROP 2 LAST PATH I92
J 0
(-6700 2200);
DISPLAY 1.021277 (-6700 2200);
PAINT ORANGE (-6700 2200);
DISPLAY INVISIBLE (-6700 2200);
FORCEPROP 1 LAST COMMENT_BODY TRUE
J 0
(-6650 2050);
DISPLAY 0.872340 (-6650 2050);
PAINT GREEN (-6650 2050);
DISPLAY INVISIBLE (-6650 2050);
FORCEADD OFFPAGE..1
(-6750 1975);
FORCEPROP 2 LAST $XR0 114 
J 0
(-7002 1975);
DISPLAY 0.638298 (-7002 1975);
PAINT MONO (-7002 1975);
FORCEPROP 2 LAST CDS_LIB mstr_standard
J 0
(-6750 1975);
PAINT ORANGE (-6750 1975);
DISPLAY INVISIBLE (-6750 1975);
FORCEPROP 1 LAST OFFPAGE TRUE
J 0
(-6425 1850);
DISPLAY 0.872340 (-6425 1850);
PAINT GREEN (-6425 1850);
DISPLAY INVISIBLE (-6425 1850);
FORCEPROP 1 LAST COMMENT_BODY TRUE
J 0
(-6625 1875);
DISPLAY 0.872340 (-6625 1875);
PAINT GREEN (-6625 1875);
DISPLAY INVISIBLE (-6625 1875);
FORCEPROP 2 LAST PATH I93
J 0
(-6700 2050);
DISPLAY 1.021277 (-6700 2050);
PAINT ORANGE (-6700 2050);
DISPLAY INVISIBLE (-6700 2050);
FORCEADD OFFPAGE..1
(-6750 1925);
FORCEPROP 2 LAST $XR0 114 
J 0
(-7002 1925);
DISPLAY 0.638298 (-7002 1925);
PAINT MONO (-7002 1925);
FORCEPROP 2 LAST CDS_LIB mstr_standard
J 0
(-6750 1925);
PAINT ORANGE (-6750 1925);
DISPLAY INVISIBLE (-6750 1925);
FORCEPROP 2 LAST PATH I94
J 0
(-6700 2000);
DISPLAY 1.021277 (-6700 2000);
PAINT ORANGE (-6700 2000);
DISPLAY INVISIBLE (-6700 2000);
FORCEPROP 1 LAST OFFPAGE TRUE
J 0
(-6425 1800);
DISPLAY 0.872340 (-6425 1800);
PAINT GREEN (-6425 1800);
DISPLAY INVISIBLE (-6425 1800);
FORCEPROP 1 LAST COMMENT_BODY TRUE
J 0
(-6625 1825);
DISPLAY 0.872340 (-6625 1825);
PAINT GREEN (-6625 1825);
DISPLAY INVISIBLE (-6625 1825);
FORCEADD CAD_NOTE..1
(-2875 4950);
FORCEPROP 0 LAST L7 SPI_NIC_MOSI_R
J 0
(-3025 4550);
DISPLAY 0.808511 (-3025 4550);
PAINT ORANGE (-3025 4550);
FORCEPROP 0 LAST L8 SPI_NIC_CS_R_N
J 0
(-3025 4500);
DISPLAY 0.808511 (-3025 4500);
PAINT ORANGE (-3025 4500);
FORCEPROP 0 LAST L9 SPI_NIC_SCLK_R
J 0
(-3025 4450);
DISPLAY 0.808511 (-3025 4450);
PAINT ORANGE (-3025 4450);
FORCEPROP 0 LAST L1 PLACE SERIES RESISTORS ON THE FOLLOWING
J 0
(-3025 4850);
DISPLAY 0.808511 (-3025 4850);
PAINT ORANGE (-3025 4850);
FORCEPROP 0 LAST L2 NETS WITHIN TWO INCHES OF SPRINGVILLE:
J 0
(-3025 4800);
DISPLAY 0.808511 (-3025 4800);
PAINT ORANGE (-3025 4800);
FORCEPROP 0 LAST L3 RMII_PCH_SPRNGVLLE_ARB_IN_R
J 0
(-3025 4750);
DISPLAY 0.808511 (-3025 4750);
PAINT ORANGE (-3025 4750);
FORCEPROP 0 LAST L4 RMII_BMC_PCH_SPRNGVLLE_CRSDV_R
J 0
(-3025 4700);
DISPLAY 0.808511 (-3025 4700);
PAINT ORANGE (-3025 4700);
FORCEPROP 0 LAST L5 RMII_SPNGVLLE_BMC-PCH_RXD1_R
J 0
(-3025 4650);
DISPLAY 0.808511 (-3025 4650);
PAINT ORANGE (-3025 4650);
FORCEPROP 0 LAST L6 RMII_SPRNGVLLE_BMC_PCH_RXD0_R
J 0
(-3025 4600);
DISPLAY 0.808511 (-3025 4600);
PAINT ORANGE (-3025 4600);
FORCEPROP 1 LAST COMMENT_BODY TRUE
J 0
(-2850 5050);
DISPLAY 0.978723 (-2850 5050);
PAINT ORANGE (-2850 5050);
DISPLAY INVISIBLE (-2850 5050);
FORCEPROP 2 LAST CDS_LIB mstr_symbols
J 0
(-2875 4950);
PAINT ORANGE (-2875 4950);
DISPLAY INVISIBLE (-2875 4950);
FORCEADD CAD_NOTE..1
(-5650 1650);
FORCEPROP 0 LAST L1 PLACE THESE CAPS NEAR PCH
J 0
(-5800 1550);
DISPLAY 0.808511 (-5800 1550);
PAINT ORANGE (-5800 1550);
FORCEPROP 2 LAST CDS_LIB mstr_symbols
J 0
(-5650 1650);
PAINT ORANGE (-5650 1650);
DISPLAY INVISIBLE (-5650 1650);
FORCEPROP 1 LAST COMMENT_BODY TRUE
J 0
(-5625 1750);
DISPLAY 0.978723 (-5625 1750);
PAINT ORANGE (-5625 1750);
DISPLAY INVISIBLE (-5625 1750);
FORCEADD DNS..2
(-1920 870);
PAINT RED (-1920 870);
FORCEPROP 1 LAST COMMENT_BODY TRUE
R 1
J 0
(-1845 645);
DISPLAY 0.872340 (-1845 645);
PAINT GREEN (-1845 645);
DISPLAY INVISIBLE (-1845 645);
FORCEPROP 2 LAST CDS_LIB mstr_misc
J 0
(-1920 870);
PAINT ORANGE (-1920 870);
DISPLAY INVISIBLE (-1920 870);
FORCEADD CAD_NOTE..1
(-4375 1575);
FORCEPROP 0 LAST L2 NEAR THE BMC
J 0
(-4525 1400);
DISPLAY 0.808511 (-4525 1400);
PAINT ORANGE (-4525 1400);
FORCEPROP 0 LAST L1 PLACE CAPS ON PE_PCH_SPRV_RX_DP/DN
J 0
(-4525 1475);
DISPLAY 0.808511 (-4525 1475);
PAINT ORANGE (-4525 1475);
FORCEPROP 2 LAST CDS_LIB mstr_symbols
J 0
(-4375 1575);
PAINT ORANGE (-4375 1575);
DISPLAY INVISIBLE (-4375 1575);
FORCEPROP 1 LAST COMMENT_BODY TRUE
J 0
(-4350 1675);
DISPLAY 0.978723 (-4350 1675);
PAINT ORANGE (-4350 1675);
DISPLAY INVISIBLE (-4350 1675);
FORCEADD DNS..2
(-3570 870);
PAINT RED (-3570 870);
FORCEPROP 1 LAST COMMENT_BODY TRUE
R 1
J 0
(-3495 645);
DISPLAY 0.872340 (-3495 645);
PAINT GREEN (-3495 645);
DISPLAY INVISIBLE (-3495 645);
FORCEPROP 2 LAST CDS_LIB mstr_misc
J 0
(-3570 870);
PAINT ORANGE (-3570 870);
DISPLAY INVISIBLE (-3570 870);
FORCEADD DNS..2
(-1595 870);
PAINT RED (-1595 870);
FORCEPROP 1 LAST COMMENT_BODY TRUE
R 1
J 0
(-1520 645);
DISPLAY 0.872340 (-1520 645);
PAINT GREEN (-1520 645);
DISPLAY INVISIBLE (-1520 645);
FORCEPROP 2 LAST CDS_LIB mstr_misc
J 0
(-1595 870);
PAINT ORANGE (-1595 870);
DISPLAY INVISIBLE (-1595 870);
FORCEADD DNS..2
(-5795 3720);
PAINT RED (-5795 3720);
FORCEPROP 1 LAST COMMENT_BODY TRUE
R 1
J 0
(-5720 3495);
DISPLAY 0.872340 (-5720 3495);
PAINT GREEN (-5720 3495);
DISPLAY INVISIBLE (-5720 3495);
FORCEPROP 2 LAST CDS_LIB mstr_misc
J 0
(-5795 3720);
PAINT ORANGE (-5795 3720);
DISPLAY INVISIBLE (-5795 3720);
FORCEADD CAD_NOTE..1
(-2525 1300);
FORCEPROP 0 LAST L2 NEAR PCH
J 0
(-2675 1150);
DISPLAY 0.808511 (-2675 1150);
PAINT ORANGE (-2675 1150);
FORCEPROP 0 LAST L1 PLACE THIS RESISTOR
J 0
(-2675 1200);
DISPLAY 0.808511 (-2675 1200);
PAINT ORANGE (-2675 1200);
FORCEPROP 1 LAST COMMENT_BODY TRUE
J 0
(-2500 1400);
DISPLAY 0.978723 (-2500 1400);
PAINT ORANGE (-2500 1400);
DISPLAY INVISIBLE (-2500 1400);
FORCEPROP 2 LAST CDS_LIB mstr_symbols
J 0
(-2525 1300);
PAINT ORANGE (-2525 1300);
DISPLAY INVISIBLE (-2525 1300);
FORCEADD DESIGN_NOTE..1
(-7700 4875);
FORCEPROP 0 LAST L2 C1 = C2 = 2 * [CLOAD-CSTRAY]
J 0
(-7900 4725);
DISPLAY 0.638298 (-7900 4725);
PAINT ORANGE (-7900 4725);
FORCEPROP 0 LAST L1 SHUNT CAPACITORS CAN BE CALCULATED USING THE FOLLOWING EQUATION
J 0
(-7900 4775);
DISPLAY 0.638298 (-7900 4775);
PAINT ORANGE (-7900 4775);
FORCEPROP 0 LAST L4 AND CSTRAY IS THE CAPACITANCE OF SOLDER PADS, TRACES AND I210 PACKAGE
J 0
(-7900 4625);
DISPLAY 0.638298 (-7900 4625);
PAINT ORANGE (-7900 4625);
FORCEPROP 0 LAST L3 WHERE CLOAD IS THE LOAD CAPACITANCE OF THE CRYSTAL (18PF FOR D71700-031)
J 0
(-7900 4675);
DISPLAY 0.638298 (-7900 4675);
PAINT ORANGE (-7900 4675);
FORCEPROP 0 LAST L6 WILL NEED TO RE CALCULATE THIS VALUE WHEN LAYOUT HAS BEEN DONE
J 0
(-7900 4525);
DISPLAY 0.638298 (-7900 4525);
PAINT ORANGE (-7900 4525);
FORCEPROP 0 LAST L5 TYPICAL CSTRAY IS 3PF TO 7PF
J 0
(-7900 4575);
DISPLAY 0.638298 (-7900 4575);
PAINT ORANGE (-7900 4575);
FORCEPROP 2 LAST CDS_LIB mstr_symbols
J 0
(-7700 4875);
PAINT ORANGE (-7700 4875);
DISPLAY INVISIBLE (-7700 4875);
FORCEPROP 1 LAST COMMENT_BODY TRUE
J 0
(-7675 4975);
DISPLAY 0.978723 (-7675 4975);
PAINT ORANGE (-7675 4975);
DISPLAY INVISIBLE (-7675 4975);
FORCEADD DNS..2
(-5270 870);
PAINT RED (-5270 870);
FORCEPROP 1 LAST COMMENT_BODY TRUE
R 1
J 0
(-5195 645);
DISPLAY 0.872340 (-5195 645);
PAINT GREEN (-5195 645);
DISPLAY INVISIBLE (-5195 645);
FORCEPROP 2 LAST CDS_LIB mstr_misc
J 0
(-5270 870);
PAINT ORANGE (-5270 870);
DISPLAY INVISIBLE (-5270 870);
FORCEADD DESIGN_NOTE..1
(-7700 4450);
FORCEPROP 0 LAST L1 FOR -IS SKU:
J 0
(-7900 4350);
DISPLAY 0.638298 (-7900 4350);
PAINT ORANGE (-7900 4350);
FORCEPROP 0 LAST L3 STUFF R1T33
J 0
(-7900 4250);
DISPLAY 0.638298 (-7900 4250);
PAINT ORANGE (-7900 4250);
FORCEPROP 0 LAST L4 DE-POP R1T34
J 0
(-7900 4200);
DISPLAY 0.638298 (-7900 4200);
PAINT ORANGE (-7900 4200);
FORCEPROP 0 LAST L2 DE-POP R1T32
J 0
(-7900 4300);
DISPLAY 0.638298 (-7900 4300);
PAINT ORANGE (-7900 4300);
FORCEPROP 0 LAST L5 DEFAULT CONFIG IS FOR -AT SKU
J 0
(-7900 4100);
DISPLAY 0.638298 (-7900 4100);
PAINT ORANGE (-7900 4100);
FORCEPROP 2 LAST CDS_LIB mstr_symbols
J 0
(-7700 4450);
PAINT ORANGE (-7700 4450);
DISPLAY INVISIBLE (-7700 4450);
FORCEPROP 1 LAST COMMENT_BODY TRUE
J 0
(-7675 4550);
DISPLAY 0.978723 (-7675 4550);
PAINT ORANGE (-7675 4550);
DISPLAY INVISIBLE (-7675 4550);
FORCEADD INTEL_CORP_BPAGE..1
(50 25);
FORCEPROP 1 LAST CDS_CON_LAST_MODIFIED Tue Dec 01 11:52:02 2015
J 0
(-1075 550);
DISPLAY 2.659574 (-1075 550);
PAINT GREEN (-1075 550);
DISPLAY INVISIBLE (-1075 550);
FORCEPROP 1 LAST CUSTOM_TXT_CDS <CURRENT_DESIGN_SHEET> OF <TOTAL_DESIGN_SHEETS>
J 0
(-450 50);
PAINT GREEN (-450 50);
FORCEPROP 2 LAST CUSTOM_TXT_CDS <XR_PAGE_TITLE>
J 0
(-7840 5275);
DISPLAY 0.638298 (-7840 5275);
PAINT PINK (-7840 5275);
DISPLAY INVISIBLE (-7840 5275);
FORCEPROP 2 LAST CUSTOM_TXT_CDS <CON_LAST_MODIFIED>
J 0
(-1875 375);
DISPLAY 0.765957 (-1875 375);
PAINT ORANGE (-1875 375);
FORCEPROP 1 LAST SCH_TITLE LAN SPRINGVILLE I210 (1/3)
J 0
(-7900 75);
DISPLAY 1.212766 (-7900 75);
PAINT GREEN (-7900 75);
FORCEPROP 1 LAST SCH_ADDRESS1 2200 Mission College Blvd.
J 0
(-3925 150);
DISPLAY 0.617021 (-3925 150);
PAINT GREEN (-3925 150);
FORCEPROP 1 LAST SCH_ADDRESS2 P.O. BOX 58119
J 0
(-3925 100);
DISPLAY 0.617021 (-3925 100);
PAINT GREEN (-3925 100);
FORCEPROP 1 LAST SCH_ADDRESS3 Santa Clara, CA 95052-8119
J 0
(-3925 50);
DISPLAY 0.617021 (-3925 50);
PAINT GREEN (-3925 50);
FORCEPROP 1 LAST SCH_REV 2.420
J 0
(-200 175);
DISPLAY 0.978723 (-200 175);
PAINT YELLOW (-200 175);
FORCEPROP 1 LAST SCH_DEPT BESD
J 1
(-4400 125);
DISPLAY 1.212766 (-4400 125);
PAINT YELLOW (-4400 125);
FORCEPROP 1 LAST SCH_NUMBER H4694802
J 0
(-1250 175);
DISPLAY 1.212766 (-1250 175);
PAINT YELLOW (-1250 175);
FORCEPROP 2 LAST PAGE_BORDER TRUE
J 0
(-7840 5275);
DISPLAY 0.425532 (-7840 5275);
PAINT PINK (-7840 5275);
DISPLAY INVISIBLE (-7840 5275);
FORCEPROP 1 LAST COMMENT_BODY TRUE
J 0
(62 37);
DISPLAY 0.319149 (62 37);
PAINT GREEN (62 37);
DISPLAY INVISIBLE (62 37);
FORCEPROP 2 LAST CDS_LIB mstr_symbols
J 0
(50 25);
DISPLAY 0.489362 (50 25);
PAINT ORANGE (50 25);
DISPLAY INVISIBLE (50 25);
FORCEPROP 2 LAST CDS_XR_PAGE_TITLE CR-139 : @BASEBOARD_FAB2_LIB.BASEBOARD_FAB2(SCH_1):PAGE139
J 0
(-7840 5275);
DISPLAY 0.638298 (-7840 5275);
PAINT PINK (-7840 5275);
DISPLAY INVISIBLE (-7840 5275);
WIRE 16 -1 (-7325 1175)(-7325 975);
WIRE 16 -1 (-7750 1175)(-7750 975);
WIRE 16 -1 (-6725 3550)(-6725 3650);
WIRE 16 -1 (-6325 3800)(-6325 3875);
WIRE 16 -1 (-5975 4100)(-5975 4175);
WIRE 16 -1 (-4025 775)(-4025 675);
WIRE 16 -1 (-4025 675)(-4275 675);
WIRE 16 -1 (-4275 675)(-4275 775);
WIRE 16 -1 (-4275 675)(-4525 675);
WIRE 16 -1 (-4525 675)(-4525 775);
WIRE 16 -1 (-4525 675)(-4775 675);
WIRE 16 -1 (-4775 675)(-4775 775);
WIRE 16 -1 (-4775 675)(-5025 675);
WIRE 16 -1 (-5025 675)(-5025 775);
WIRE 16 -1 (-5025 675)(-5275 675);
WIRE 16 -1 (-5275 675)(-5275 775);
WIRE 16 -1 (-5275 675)(-5275 625);
WIRE 16 -1 (-2325 975)(-2325 1050);
WIRE 16 -1 (-2325 1050)(-2575 1050);
WIRE 16 -1 (-2575 1050)(-2825 1050);
WIRE 16 -1 (-2575 1050)(-2575 975);
WIRE 16 -1 (-2825 1050)(-2825 975);
WIRE 16 -1 (-2825 1050)(-3075 1050);
WIRE 16 -1 (-3075 1050)(-3325 1050);
WIRE 16 -1 (-3075 1050)(-3075 975);
WIRE 16 -1 (-3325 1050)(-3575 1050);
WIRE 16 -1 (-3325 1050)(-3325 975);
WIRE 16 -1 (-3575 975)(-3575 1050);
WIRE 16 -1 (-3575 1050)(-3575 1125);
WIRE 16 -1 (-2325 775)(-2325 675);
WIRE 16 -1 (-2325 675)(-2575 675);
WIRE 16 -1 (-2575 675)(-2575 775);
WIRE 16 -1 (-2575 675)(-2825 675);
WIRE 16 -1 (-2825 675)(-2825 775);
WIRE 16 -1 (-2825 675)(-3075 675);
WIRE 16 -1 (-3075 675)(-3075 775);
WIRE 16 -1 (-3075 675)(-3325 675);
WIRE 16 -1 (-3325 675)(-3325 775);
WIRE 16 -1 (-3325 675)(-3575 675);
WIRE 16 -1 (-3575 675)(-3575 775);
WIRE 16 -1 (-3575 675)(-3575 625);
WIRE 16 -1 (-350 975)(-350 1050);
WIRE 16 -1 (-350 1050)(-600 1050);
WIRE 16 -1 (-600 1050)(-850 1050);
WIRE 16 -1 (-600 1050)(-600 975);
WIRE 16 -1 (-850 1050)(-850 975);
WIRE 16 -1 (-850 1050)(-1100 1050);
WIRE 16 -1 (-1100 1050)(-1350 1050);
WIRE 16 -1 (-1100 1050)(-1100 975);
WIRE 16 -1 (-1350 1050)(-1600 1050);
WIRE 16 -1 (-1350 1050)(-1350 975);
WIRE 16 -1 (-1600 975)(-1600 1050);
WIRE 16 -1 (-1925 1050)(-1600 1050);
WIRE 16 -1 (-1925 1050)(-1925 1100);
WIRE 16 -1 (-1925 1050)(-1925 975);
WIRE 16 -1 (-350 775)(-350 675);
WIRE 16 -1 (-350 675)(-600 675);
WIRE 16 -1 (-600 675)(-600 775);
WIRE 16 -1 (-600 675)(-850 675);
WIRE 16 -1 (-850 675)(-850 775);
WIRE 16 -1 (-850 675)(-1100 675);
WIRE 16 -1 (-1100 675)(-1100 775);
WIRE 16 -1 (-1100 675)(-1350 675);
WIRE 16 -1 (-1350 675)(-1350 775);
WIRE 16 -1 (-1350 675)(-1600 675);
WIRE 16 -1 (-1600 675)(-1600 775);
WIRE 16 -1 (-1925 675)(-1600 675);
WIRE 16 -1 (-1925 775)(-1925 675);
WIRE 16 -1 (-1925 675)(-1925 625);
WIRE 16 -1 (-900 3125)(-900 3000);
WIRE 16 -1 (-7025 3225)(-7025 3325);
WIRE 16 -1 (-7025 3325)(-7275 3325);
WIRE 16 -1 (-7275 3325)(-7275 3225);
WIRE 16 -1 (-7525 3325)(-7275 3325);
WIRE 16 -1 (-7525 3225)(-7525 3325);
WIRE 16 -1 (-7525 3325)(-7525 3400);
WIRE 16 -1 (-1400 2825)(-1175 2825);
WIRE 16 -1 (-1175 2825)(-1175 3150);
WIRE 16 -1 (-6450 3475)(-5100 3475);
WIRE 16 -1 (-6450 3475)(-6450 3525);
WIRE 16 -1 (-6450 3525)(-5700 3525);
WIRE 16 -1 (-6450 3525)(-6450 3575);
WIRE 16 -1 (-6450 3575)(-5100 3575);
WIRE 16 -1 (-6450 3625)(-6450 3575);
WIRE 16 -1 (-6450 3625)(-5100 3625);
WIRE 16 -1 (-6450 3675)(-6450 3625);
WIRE 16 -1 (-6450 3675)(-5100 3675);
WIRE 16 -1 (-6450 3675)(-6450 3900);
WIRE 16 -1 (-6725 3900)(-6450 3900);
WIRE 16 -1 (-6725 3850)(-6725 3900);
WIRE 16 -1 (-6725 3950)(-6725 3900);
WIRE 16 -1 (-900 4000)(-900 3925);
WIRE 16 -1 (-4025 975)(-4025 1050);
WIRE 16 -1 (-4025 1050)(-4275 1050);
WIRE 16 -1 (-4275 1050)(-4525 1050);
WIRE 16 -1 (-4275 1050)(-4275 975);
WIRE 16 -1 (-4525 1050)(-4775 1050);
WIRE 16 -1 (-4525 1050)(-4525 975);
WIRE 16 -1 (-4775 1050)(-5025 1050);
WIRE 16 -1 (-4775 1050)(-4775 975);
WIRE 16 -1 (-5025 1050)(-5025 975);
WIRE 16 -1 (-5025 1050)(-5275 1050);
WIRE 16 -1 (-5275 975)(-5275 1050);
WIRE 16 -1 (-5275 1050)(-5275 1125);
WIRE 16 -1 (-1000 4650)(-1000 4575);
WIRE 16 -1 (-6350 1000)(-6350 875);
WIRE 16 -1 (-1900 1550)(-1900 1425);
WIRE 16 -1 (-2875 1425)(-2875 1300);
WIRE 16 -1 (-875 1450)(-875 1325);
WIRE 16 -1 (-5725 4125)(-5725 4025);
WIRE 16 -1 (-5725 4125)(-5100 4125);
WIRE 16 -1 (-5725 4175)(-5725 4125);
WIRE 16 -1 (-5725 4025)(-5700 4025);
WIRE 16 -1 (-5725 4175)(-5100 4175);
WIRE 16 -1 (-5725 4225)(-5725 4175);
WIRE 16 -1 (-5725 4225)(-5100 4225);
WIRE 16 -1 (-5725 4275)(-5725 4225);
WIRE 16 -1 (-5725 4275)(-5100 4275);
WIRE 16 -1 (-5725 4275)(-5725 4425);
WIRE 16 -1 (-5975 4425)(-5725 4425);
WIRE 16 -1 (-5725 4425)(-5725 4475);
WIRE 16 -1 (-5975 4375)(-5975 4425);
WIRE 16 -1 (-5900 3725)(-6075 3725);
WIRE 16 -1 (-6075 3725)(-6075 3775);
WIRE 16 -1 (-6075 3775)(-5100 3775);
WIRE 16 -1 (-6075 3775)(-6075 3875);
WIRE 16 -1 (-5900 3875)(-6075 3875);
WIRE 16 -1 (-6075 3875)(-6075 3925);
WIRE 16 -1 (-6075 3925)(-6075 4150);
WIRE 16 -1 (-6075 3925)(-5100 3925);
WIRE 16 -1 (-6325 4150)(-6075 4150);
FORCEPROP 0 LAST VOLTAGE +1.5V
J 0
(-6200 4200);
DISPLAY 1.021277 (-6200 4200);
PAINT SKYBLUE (-6200 4200);
DISPLAY INVISIBLE (-6200 4200);
WIRE 16 -1 (-6325 4075)(-6325 4150);
WIRE 16 -1 (-6325 4150)(-6325 4250);
WIRE 16 -1 (-3175 1875)(-3300 1875);
WIRE 16 -1 (-3175 1475)(-3175 1875);
WIRE 16 -1 (-6000 3375)(-5100 3375);
FORCEPROP 2 LAST SIG_NAME XTAL_25MHZ_IN_R
J 0
(-6000 3385);
DISPLAY 0.617021 (-6000 3385);
PAINT ORANGE (-6000 3385);
WIRE 16 -1 (-6000 3225)(-5100 3225);
FORCEPROP 2 LAST SIG_NAME XTAL_25MHZ_OUT
J 0
(-6000 3235);
DISPLAY 0.617021 (-6000 3235);
PAINT ORANGE (-6000 3235);
WIRE 16 -1 (-1000 4250)(-475 4250);
FORCEPROP 2 LAST SIG_NAME IRQ_LOM_ALERT_N
J 0
(-960 4260);
DISPLAY 0.617021 (-960 4260);
PAINT ORANGE (-960 4260);
WIRE 16 -1 (-1000 4375)(-1000 4250);
WIRE 16 -1 (-2675 4275)(-3300 4275);
FORCEPROP 2 LAST SIG_NAME NIC_SER_P_MDI_3_DP
J 0
(-3185 4285);
DISPLAY 0.617021 (-3185 4285);
PAINT ORANGE (-3185 4285);
WIRE 16 -1 (-2675 4225)(-3300 4225);
FORCEPROP 2 LAST SIG_NAME NIC_SER_N_MDI_3_DN
J 0
(-3185 4235);
DISPLAY 0.617021 (-3185 4235);
PAINT ORANGE (-3185 4235);
WIRE 16 -1 (-2675 4175)(-3300 4175);
FORCEPROP 2 LAST SIG_NAME NIC_SET_P_MDI_2_DP
J 0
(-3185 4185);
DISPLAY 0.617021 (-3185 4185);
PAINT ORANGE (-3185 4185);
WIRE 16 -1 (-2675 4125)(-3300 4125);
FORCEPROP 2 LAST SIG_NAME NIC_SET_N_MDI_2_DN
J 0
(-3185 4135);
DISPLAY 0.617021 (-3185 4135);
PAINT ORANGE (-3185 4135);
WIRE 16 -1 (-900 3600)(-375 3600);
WIRE 16 -1 (-900 3725)(-900 3600);
FORCEPROP 2 LAST SIG_NAME PU_SPRV_LAN_PWR_GOOD
J 0
(-885 3610);
DISPLAY 0.617021 (-885 3610);
PAINT ORANGE (-885 3610);
WIRE 16 -1 (-900 3400)(-525 3400);
FORCEPROP 2 LAST SIG_NAME PD_SPRV_RSET
J 0
(-785 3410);
DISPLAY 0.617021 (-785 3410);
PAINT ORANGE (-785 3410);
WIRE 16 -1 (-900 3400)(-900 3325);
WIRE 16 -1 (-1450 2325)(-925 2325);
FORCEPROP 2 LAST SIG_NAME SPI_NIC_CS_N
J 0
(-1185 2335);
DISPLAY 0.617021 (-1185 2335);
PAINT ORANGE (-1185 2335);
WIRE 16 -1 (-1650 2475)(-925 2475);
FORCEPROP 2 LAST SIG_NAME RMII_SPRNGVLLE_BMC_PCH_RXD0
J 2
(-925 2485);
DISPLAY 0.617021 (-925 2485);
PAINT ORANGE (-925 2485);
WIRE 16 -1 (-1975 2725)(-925 2725);
FORCEPROP 2 LAST SIG_NAME RMII_PCH_SPRNGVLLE_ARB_IN
J 0
(-1635 2735);
DISPLAY 0.617021 (-1635 2735);
PAINT ORANGE (-1635 2735);
WIRE 16 -1 (-1550 2075)(-950 2075);
FORCEPROP 2 LAST SIG_NAME PE_PCH_SPRV_RX_C_DN
J 0
(-1335 2085);
DISPLAY 0.617021 (-1335 2085);
PAINT ORANGE (-1335 2085);
WIRE 16 -1 (-875 1725)(-500 1725);
FORCEPROP 2 LAST SIG_NAME RMII_BMC_PCH_SPRNGVLLE_CRSDV
J 0
(-1085 1735);
DISPLAY 0.617021 (-1085 1735);
PAINT ORANGE (-1085 1735);
WIRE 16 -1 (-875 1725)(-875 1650);
WIRE 16 -1 (-1900 1825)(-1525 1825);
FORCEPROP 2 LAST SIG_NAME RMII_BMC_PCH_SPRNGVLLE_TXEN
J 0
(-2085 1835);
DISPLAY 0.617021 (-2085 1835);
PAINT ORANGE (-2085 1835);
WIRE 16 -1 (-1900 1825)(-1900 1750);
WIRE 16 -1 (-3300 2075)(-1750 2075);
FORCEPROP 2 LAST SIG_NAME PE_PCH_SPRV_RX_DN
J 0
(-3210 2085);
DISPLAY 0.617021 (-3210 2085);
PAINT ORANGE (-3210 2085);
FORCEPROP 2 LASTPROP $XRERR UNIQUE?
J 0
(-3450 2085);
DISPLAY 0.638298 (-3450 2085);
PAINT MONO (-3450 2085);
DISPLAY INVISIBLE (-3450 2085);
WIRE 16 -1 (-3300 2325)(-1650 2325);
FORCEPROP 2 LAST SIG_NAME SPI_NIC_CS_R_N
J 0
(-3210 2335);
DISPLAY 0.617021 (-3210 2335);
PAINT ORANGE (-3210 2335);
FORCEPROP 2 LASTPROP $XRERR UNIQUE?
J 0
(-3450 2335);
DISPLAY 0.638298 (-3450 2335);
PAINT MONO (-3450 2335);
DISPLAY INVISIBLE (-3450 2335);
WIRE 16 -1 (-3300 2475)(-1850 2475);
FORCEPROP 2 LAST SIG_NAME RMII_SPRNGVLLE_BMC_PCH_RXD0_R
J 0
(-3235 2485);
DISPLAY 0.617021 (-3235 2485);
PAINT ORANGE (-3235 2485);
FORCEPROP 2 LASTPROP $XRERR UNIQUE?
J 0
(-3475 2485);
DISPLAY 0.638298 (-3475 2485);
PAINT MONO (-3475 2485);
DISPLAY INVISIBLE (-3475 2485);
WIRE 16 -1 (-3300 2825)(-1600 2825);
FORCEPROP 2 LAST SIG_NAME PU_JTAG_SPRV_TDO
J 2
(-2050 2835);
DISPLAY 0.617021 (-2050 2835);
PAINT ORANGE (-2050 2835);
FORCEPROP 2 LASTPROP $XRERR UNIQUE?
J 0
(-2290 2835);
DISPLAY 0.638298 (-2290 2835);
PAINT MONO (-2290 2835);
DISPLAY INVISIBLE (-2290 2835);
WIRE 16 -1 (-2325 2375)(-925 2375);
FORCEPROP 2 LAST SIG_NAME SPI_NIC_MOSI
J 0
(-1185 2385);
DISPLAY 0.617021 (-1185 2385);
PAINT ORANGE (-1185 2385);
WIRE 16 -1 (-2300 2275)(-925 2275);
FORCEPROP 2 LAST SIG_NAME SPI_NIC_SCLK
J 0
(-1185 2285);
DISPLAY 0.617021 (-1185 2285);
PAINT ORANGE (-1185 2285);
WIRE 16 -1 (-2300 2675)(-925 2675);
FORCEPROP 2 LAST SIG_NAME RMII_BMC_PCH_SPRNGVLLE_CRSDV
J 0
(-1635 2685);
DISPLAY 0.617021 (-1635 2685);
PAINT ORANGE (-1635 2685);
WIRE 16 -1 (-2175 2525)(-925 2525);
FORCEPROP 2 LAST SIG_NAME RMII_SPRNGVLLE_BMC_PCH_RXD1
J 2
(-925 2535);
DISPLAY 0.617021 (-925 2535);
PAINT ORANGE (-925 2535);
WIRE 16 -1 (-2300 2125)(-950 2125);
FORCEPROP 2 LAST SIG_NAME PE_PCH_SPRV_RX_C_DP
J 0
(-1335 2135);
DISPLAY 0.617021 (-1335 2135);
PAINT ORANGE (-1335 2135);
WIRE 16 -1 (-2725 3600)(-2725 3625);
WIRE 16 -1 (-2725 3625)(-3300 3625);
FORCEPROP 2 LAST SIG_NAME A_CTOP
J 0
(-3160 3635);
DISPLAY 0.617021 (-3160 3635);
PAINT ORANGE (-3160 3635);
FORCEPROP 2 LASTPROP $XRERR UNIQUE?
J 0
(-3400 3635);
DISPLAY 0.638298 (-3400 3635);
PAINT MONO (-3400 3635);
DISPLAY INVISIBLE (-3400 3635);
WIRE 16 -1 (-2725 3400)(-2725 3375);
WIRE 16 -1 (-2725 3375)(-3300 3375);
FORCEPROP 2 LAST SIG_NAME A_CBOT
J 0
(-3160 3385);
DISPLAY 0.617021 (-3160 3385);
PAINT ORANGE (-3160 3385);
FORCEPROP 2 LASTPROP $XRERR UNIQUE?
J 0
(-3400 3385);
DISPLAY 0.638298 (-3400 3385);
PAINT MONO (-3400 3385);
DISPLAY INVISIBLE (-3400 3385);
WIRE 16 -1 (-3300 2125)(-2500 2125);
FORCEPROP 2 LAST SIG_NAME PE_PCH_SPRV_RX_DP
J 0
(-3210 2135);
DISPLAY 0.617021 (-3210 2135);
PAINT ORANGE (-3210 2135);
FORCEPROP 2 LASTPROP $XRERR UNIQUE?
J 0
(-3450 2135);
DISPLAY 0.638298 (-3450 2135);
PAINT MONO (-3450 2135);
DISPLAY INVISIBLE (-3450 2135);
WIRE 16 -1 (-3300 3225)(-2400 3225);
FORCEPROP 2 LAST SIG_NAME TP_SPRV_SDP2
J 2
(-2400 3235);
DISPLAY 0.617021 (-2400 3235);
PAINT ORANGE (-2400 3235);
FORCEPROP 2 LASTPROP $XRERR UNIQUE?
J 0
(-2370 3225);
DISPLAY 0.638298 (-2370 3225);
PAINT MONO (-2370 3225);
DISPLAY INVISIBLE (-2370 3225);
WIRE 16 -1 (-3300 3125)(-2400 3125);
FORCEPROP 2 LAST SIG_NAME TP_SPRV_SDP0
J 2
(-2400 3135);
DISPLAY 0.617021 (-2400 3135);
PAINT ORANGE (-2400 3135);
FORCEPROP 2 LASTPROP $XRERR UNIQUE?
J 0
(-2370 3125);
DISPLAY 0.638298 (-2370 3125);
PAINT MONO (-2370 3125);
DISPLAY INVISIBLE (-2370 3125);
WIRE 16 -1 (-3300 2275)(-2500 2275);
FORCEPROP 2 LAST SIG_NAME SPI_NIC_SCLK_R
J 0
(-3210 2285);
DISPLAY 0.617021 (-3210 2285);
PAINT ORANGE (-3210 2285);
FORCEPROP 2 LASTPROP $XRERR UNIQUE?
J 0
(-3450 2285);
DISPLAY 0.638298 (-3450 2285);
PAINT MONO (-3450 2285);
DISPLAY INVISIBLE (-3450 2285);
WIRE 16 -1 (-3300 2375)(-2525 2375);
FORCEPROP 2 LAST SIG_NAME SPI_NIC_MOSI_R
J 0
(-3210 2385);
DISPLAY 0.617021 (-3210 2385);
PAINT ORANGE (-3210 2385);
FORCEPROP 2 LASTPROP $XRERR UNIQUE?
J 0
(-3450 2385);
DISPLAY 0.638298 (-3450 2385);
PAINT MONO (-3450 2385);
DISPLAY INVISIBLE (-3450 2385);
WIRE 16 -1 (-3300 2525)(-2375 2525);
FORCEPROP 2 LAST SIG_NAME RMII_SPRNGVLLE_BMC_PCH_RXD1_R
J 0
(-3260 2535);
DISPLAY 0.617021 (-3260 2535);
PAINT ORANGE (-3260 2535);
FORCEPROP 2 LASTPROP $XRERR UNIQUE?
J 0
(-3500 2535);
DISPLAY 0.638298 (-3500 2535);
PAINT MONO (-3500 2535);
DISPLAY INVISIBLE (-3500 2535);
WIRE 16 -1 (-3300 2675)(-2500 2675);
FORCEPROP 2 LAST SIG_NAME RMII_BMC_PCH_SPRNGVLLE_CRSDV_R
J 0
(-3250 2685);
DISPLAY 0.617021 (-3250 2685);
PAINT ORANGE (-3250 2685);
FORCEPROP 2 LASTPROP $XRERR UNIQUE?
J 0
(-3490 2685);
DISPLAY 0.638298 (-3490 2685);
PAINT MONO (-3490 2685);
DISPLAY INVISIBLE (-3490 2685);
WIRE 16 -1 (-3300 2725)(-2175 2725);
FORCEPROP 2 LAST SIG_NAME RMII_PCH_SPRNGVLLE_ARB_IN_R
J 0
(-3225 2735);
DISPLAY 0.617021 (-3225 2735);
PAINT ORANGE (-3225 2735);
FORCEPROP 2 LASTPROP $XRERR UNIQUE?
J 0
(-3465 2735);
DISPLAY 0.638298 (-3465 2735);
PAINT MONO (-3465 2735);
DISPLAY INVISIBLE (-3465 2735);
WIRE 16 -1 (-3300 3275)(-2400 3275);
FORCEPROP 2 LAST SIG_NAME TP_SPRV_SDP3
J 2
(-2400 3285);
DISPLAY 0.617021 (-2400 3285);
PAINT ORANGE (-2400 3285);
FORCEPROP 2 LASTPROP $XRERR UNIQUE?
J 0
(-2370 3275);
DISPLAY 0.638298 (-2370 3275);
PAINT MONO (-2370 3275);
DISPLAY INVISIBLE (-2370 3275);
WIRE 16 -1 (-3300 3175)(-2400 3175);
FORCEPROP 2 LAST SIG_NAME TP_SPRV_SDP1
J 2
(-2400 3185);
DISPLAY 0.617021 (-2400 3185);
PAINT ORANGE (-2400 3185);
FORCEPROP 2 LASTPROP $XRERR UNIQUE?
J 0
(-2370 3175);
DISPLAY 0.638298 (-2370 3175);
PAINT MONO (-2370 3175);
DISPLAY INVISIBLE (-2370 3175);
WIRE 16 -1 (-2675 4075)(-3300 4075);
FORCEPROP 2 LAST SIG_NAME NIC_MDI_SPRV_RJ45_1_DP
J 0
(-3185 4085);
DISPLAY 0.617021 (-3185 4085);
PAINT ORANGE (-3185 4085);
WIRE 16 -1 (-2675 4025)(-3300 4025);
FORCEPROP 2 LAST SIG_NAME NIC_MDI_SPRV_RJ45_1_DN
J 0
(-3185 4035);
DISPLAY 0.617021 (-3185 4035);
PAINT ORANGE (-3185 4035);
WIRE 16 -1 (-2675 3925)(-3300 3925);
FORCEPROP 2 LAST SIG_NAME NIC_MDI_SPRV_RJ45_0_DN
J 0
(-3185 3935);
DISPLAY 0.617021 (-3185 3935);
PAINT ORANGE (-3185 3935);
WIRE 16 -1 (-2675 3975)(-3300 3975);
FORCEPROP 2 LAST SIG_NAME NIC_MDI_SPRV_RJ45_0_DP
J 0
(-3185 3985);
DISPLAY 0.617021 (-3185 3985);
PAINT ORANGE (-3185 3985);
WIRE 16 -1 (-3300 3825)(-2650 3825);
FORCEPROP 2 LAST SIG_NAME LED_LAN_2_N
J 2
(-2650 3835);
DISPLAY 0.617021 (-2650 3835);
PAINT ORANGE (-2650 3835);
WIRE 16 -1 (-3300 3775)(-2650 3775);
FORCEPROP 2 LAST SIG_NAME LED_LAN_1_N
J 2
(-2650 3785);
DISPLAY 0.617021 (-2650 3785);
PAINT ORANGE (-2650 3785);
WIRE 16 -1 (-3300 3725)(-2650 3725);
FORCEPROP 2 LAST SIG_NAME LED_LAN_0_N
J 2
(-2650 3735);
DISPLAY 0.617021 (-2650 3735);
PAINT ORANGE (-2650 3735);
WIRE 16 -1 (-2400 3025)(-3300 3025);
FORCEPROP 2 LAST SIG_NAME SMB_SPRINGVILLE_STBY_LVC3_SCL
J 2
(-2375 3035);
DISPLAY 0.617021 (-2375 3035);
PAINT ORANGE (-2375 3035);
WIRE 16 -1 (-2400 2975)(-3300 2975);
FORCEPROP 2 LAST SIG_NAME SMB_SPRINGVILLE_STBY_LVC3_SDA
J 2
(-2375 2985);
DISPLAY 0.617021 (-2375 2985);
PAINT ORANGE (-2375 2985);
WIRE 16 -1 (-2400 2925)(-3300 2925);
FORCEPROP 2 LAST SIG_NAME IRQ_LOM_ALERT_N
J 2
(-2375 2935);
DISPLAY 0.617021 (-2375 2935);
PAINT ORANGE (-2375 2935);
WIRE 16 -1 (-2875 1700)(-2500 1700);
FORCEPROP 2 LAST SIG_NAME CLK_50M_CKMNG_SPRVLLE
J 0
(-2960 1710);
DISPLAY 0.617021 (-2960 1710);
PAINT ORANGE (-2960 1710);
WIRE 16 -1 (-2875 1700)(-2875 1625);
WIRE 16 -1 (-3300 1975)(-2400 1975);
FORCEPROP 2 LAST SIG_NAME NC_SPRNGVLLE_22
J 0
(-3110 1985);
DISPLAY 0.617021 (-3110 1985);
PAINT ORANGE (-3110 1985);
FORCEPROP 2 LASTPROP $XRERR UNIQUE?
J 0
(-2370 1975);
DISPLAY 0.638298 (-2370 1975);
PAINT MONO (-2370 1975);
DISPLAY INVISIBLE (-2370 1975);
WIRE 16 -1 (-5250 3525)(-5100 3525);
WIRE 16 -1 (-5250 3525)(-5250 3725);
WIRE 16 -1 (-5500 3525)(-5250 3525);
WIRE 16 -1 (-5250 3725)(-5700 3725);
FORCEPROP 0 LAST VOLTAGE 3.3
J 0
(-5600 3800);
DISPLAY 1.021277 (-5600 3800);
PAINT SKYBLUE (-5600 3800);
DISPLAY INVISIBLE (-5600 3800);
FORCEPROP 2 LAST SIG_NAME P3V3_STBY_P1V5_LAN_I210
J 0
(-5610 3735);
DISPLAY 0.617021 (-5610 3735);
PAINT ORANGE (-5610 3735);
FORCEPROP 2 LASTPROP $XRERR UNIQUE?
J 0
(-5850 3735);
DISPLAY 0.638298 (-5850 3735);
PAINT MONO (-5850 3735);
DISPLAY INVISIBLE (-5850 3735);
WIRE 16 -1 (-5900 2075)(-5100 2075);
FORCEPROP 2 LAST SIG_NAME PE_PCH_SPRV_TX_C_DN
J 0
(-5585 2085);
DISPLAY 0.617021 (-5585 2085);
PAINT ORANGE (-5585 2085);
FORCEPROP 2 LASTPROP $XRERR UNIQUE?
J 0
(-5825 2085);
DISPLAY 0.638298 (-5825 2085);
PAINT MONO (-5825 2085);
DISPLAY INVISIBLE (-5825 2085);
WIRE 16 -1 (-5675 2125)(-5100 2125);
FORCEPROP 2 LAST SIG_NAME PE_PCH_SPRV_TX_C_DP
J 0
(-5585 2135);
DISPLAY 0.617021 (-5585 2135);
PAINT ORANGE (-5585 2135);
FORCEPROP 2 LASTPROP $XRERR UNIQUE?
J 0
(-5825 2135);
DISPLAY 0.638298 (-5825 2135);
PAINT MONO (-5825 2135);
DISPLAY INVISIBLE (-5825 2135);
WIRE 16 -1 (-5500 4025)(-5100 4025);
FORCEPROP 0 LAST VOLTAGE 0.9
J 0
(-5475 4100);
DISPLAY 1.021277 (-5475 4100);
PAINT SKYBLUE (-5475 4100);
DISPLAY INVISIBLE (-5475 4100);
FORCEPROP 2 LAST SIG_NAME P0V9_LAN_I210
J 0
(-5485 4035);
DISPLAY 0.617021 (-5485 4035);
PAINT ORANGE (-5485 4035);
FORCEPROP 2 LASTPROP $XRERR UNIQUE?
J 0
(-5725 4035);
DISPLAY 0.638298 (-5725 4035);
PAINT MONO (-5725 4035);
DISPLAY INVISIBLE (-5725 4035);
WIRE 16 -1 (-5700 3875)(-5100 3875);
FORCEPROP 0 LAST VOLTAGE 1.5
J 0
(-5550 3950);
DISPLAY 1.021277 (-5550 3950);
PAINT SKYBLUE (-5550 3950);
DISPLAY INVISIBLE (-5550 3950);
FORCEPROP 2 LAST SIG_NAME P1V5_LAN_I210
J 0
(-5560 3885);
DISPLAY 0.617021 (-5560 3885);
PAINT ORANGE (-5560 3885);
FORCEPROP 2 LASTPROP $XRERR UNIQUE?
J 0
(-5800 3885);
DISPLAY 0.638298 (-5800 3885);
PAINT MONO (-5800 3885);
DISPLAY INVISIBLE (-5800 3885);
WIRE 16 -1 (-6000 3125)(-5100 3125);
FORCEPROP 2 LAST SIG_NAME FM_1GB_LOM_DISABLE_N
J 0
(-6000 3135);
DISPLAY 0.617021 (-6000 3135);
PAINT ORANGE (-6000 3135);
WIRE 16 -1 (-6000 3075)(-5100 3075);
FORCEPROP 2 LAST SIG_NAME PU_SPRV_LAN_PWR_GOOD
J 0
(-6000 3085);
DISPLAY 0.617021 (-6000 3085);
PAINT ORANGE (-6000 3085);
WIRE 16 -1 (-6000 3025)(-5100 3025);
FORCEPROP 2 LAST SIG_NAME PD_SPRV_RSET
J 0
(-6000 3035);
DISPLAY 0.617021 (-6000 3035);
PAINT ORANGE (-6000 3035);
WIRE 16 -1 (-5100 2725)(-6000 2725);
FORCEPROP 2 LAST SIG_NAME CLK_50M_CKMNG_SPRVLLE
J 0
(-5985 2735);
DISPLAY 0.617021 (-5985 2735);
PAINT ORANGE (-5985 2735);
WIRE 16 -1 (-6000 2625)(-5100 2625);
FORCEPROP 0 LAST SIG_NAME RMII_PCH_SPRNGVLLE_ARB_OUT
J 0
(-6000 2635);
DISPLAY 0.617021 (-6000 2635);
PAINT ORANGE (-6000 2635);
WIRE 16 -1 (-6000 2675)(-5100 2675);
FORCEPROP 2 LAST SIG_NAME RMII_BMC_PCH_SPRNGVLLE_TXEN
J 0
(-6000 2685);
DISPLAY 0.617021 (-6000 2685);
PAINT ORANGE (-6000 2685);
WIRE 16 3135 (-5375 1650)(-5375 2200);
WIRE 16 3135 (-4700 1650)(-5375 1650);
WIRE 16 3135 (-5375 2200)(-6175 2200);
WIRE 16 3135 (-6175 2200)(-6175 1775);
WIRE 16 3135 (-4700 1450)(-4700 1650);
WIRE 16 3135 (-5875 1450)(-4700 1450);
WIRE 16 3135 (-6175 1775)(-5875 1775);
WIRE 16 3135 (-5875 1775)(-5875 1450);
WIRE 16 -1 (-5100 2875)(-7275 2875);
FORCEPROP 2 LAST SIG_NAME PU_JTAG_SPRV_TMS
J 0
(-6000 2885);
DISPLAY 0.617021 (-6000 2885);
PAINT ORANGE (-6000 2885);
FORCEPROP 2 LASTPROP $XRERR UNIQUE?
J 0
(-6240 2885);
DISPLAY 0.638298 (-6240 2885);
PAINT MONO (-6240 2885);
DISPLAY INVISIBLE (-6240 2885);
WIRE 16 -1 (-7275 3025)(-7275 2875);
WIRE 16 -1 (-5100 2825)(-7525 2825);
FORCEPROP 2 LAST SIG_NAME PU_JTAG_SPRV_TDI
J 0
(-6000 2835);
DISPLAY 0.617021 (-6000 2835);
PAINT ORANGE (-6000 2835);
FORCEPROP 2 LASTPROP $XRERR UNIQUE?
J 0
(-6240 2835);
DISPLAY 0.638298 (-6240 2835);
PAINT MONO (-6240 2835);
DISPLAY INVISIBLE (-6240 2835);
WIRE 16 -1 (-7525 3025)(-7525 2825);
WIRE 16 -1 (-5100 2925)(-7025 2925);
FORCEPROP 2 LAST SIG_NAME PU_JTAG_SPRV_TCK
J 0
(-6000 2935);
DISPLAY 0.617021 (-6000 2935);
PAINT ORANGE (-6000 2935);
FORCEPROP 2 LASTPROP $XRERR UNIQUE?
J 0
(-6240 2935);
DISPLAY 0.638298 (-6240 2935);
PAINT MONO (-6240 2935);
DISPLAY INVISIBLE (-6240 2935);
WIRE 16 -1 (-7025 3025)(-7025 2925);
WIRE 16 -1 (-6700 2375)(-5100 2375);
FORCEPROP 2 LAST SIG_NAME SPI_NIC_MISO
J 0
(-6660 2385);
DISPLAY 0.617021 (-6660 2385);
PAINT ORANGE (-6660 2385);
WIRE 16 -1 (-6700 2225)(-5100 2225);
FORCEPROP 2 LAST SIG_NAME FM_PE_SPRV_WAKE_N
J 0
(-6685 2235);
DISPLAY 0.617021 (-6685 2235);
PAINT ORANGE (-6685 2235);
WIRE 16 -1 (-6350 675)(-6350 550);
WIRE 16 -1 (-6350 550)(-5850 550);
FORCEPROP 2 LAST SIG_NAME RST_PLTRST_SPRV_R_N
J 0
(-6185 560);
DISPLAY 0.617021 (-6185 560);
PAINT ORANGE (-6185 560);
WIRE 16 -1 (-6500 550)(-6350 550);
WIRE 16 -1 (-6700 2275)(-5100 2275);
FORCEPROP 2 LAST SIG_NAME RST_PLTRST_SPRV_R_N
J 0
(-6635 2285);
DISPLAY 0.617021 (-6635 2285);
PAINT ORANGE (-6635 2285);
WIRE 16 -1 (-6700 2475)(-5100 2475);
FORCEPROP 2 LAST SIG_NAME RMII_BMC_PCH_SPRNGVLLE_TXD0
J 0
(-6660 2485);
DISPLAY 0.617021 (-6660 2485);
PAINT ORANGE (-6660 2485);
WIRE 16 -1 (-6700 2525)(-5100 2525);
FORCEPROP 2 LAST SIG_NAME RMII_BMC_PCH_SPRNGVLLE_TXD1
J 0
(-6660 2535);
DISPLAY 0.617021 (-6660 2535);
PAINT ORANGE (-6660 2535);
WIRE 16 -1 (-6700 2075)(-6100 2075);
FORCEPROP 2 LAST SIG_NAME PE_PCH_SPRV_TX_DN
J 0
(-6610 2085);
DISPLAY 0.617021 (-6610 2085);
PAINT ORANGE (-6610 2085);
WIRE 16 -1 (-6700 2125)(-5875 2125);
FORCEPROP 2 LAST SIG_NAME PE_PCH_SPRV_TX_DP
J 0
(-6610 2135);
DISPLAY 0.617021 (-6610 2135);
PAINT ORANGE (-6610 2135);
WIRE 16 -1 (-6700 1975)(-5100 1975);
FORCEPROP 2 LAST SIG_NAME CLK_100M_SPRV_DP
J 0
(-6660 1985);
DISPLAY 0.617021 (-6660 1985);
PAINT ORANGE (-6660 1985);
WIRE 16 -1 (-6700 1925)(-5100 1925);
FORCEPROP 2 LAST SIG_NAME CLK_100M_SPRV_DN
J 0
(-6660 1935);
DISPLAY 0.617021 (-6660 1935);
PAINT ORANGE (-6660 1935);
WIRE 16 -1 (-6400 1675)(-6775 1675);
FORCEPROP 2 LAST SIG_NAME XTAL_25MHZ_IN_R
J 2
(-6400 1685);
DISPLAY 0.617021 (-6400 1685);
PAINT ORANGE (-6400 1685);
WIRE 16 -1 (-6775 1575)(-6400 1575);
FORCEPROP 2 LAST SIG_NAME XTAL_25MHZ_OUT
J 2
(-6400 1585);
DISPLAY 0.617021 (-6400 1585);
PAINT ORANGE (-6400 1585);
WIRE 16 -1 (-7075 550)(-6700 550);
FORCEPROP 2 LAST SIG_NAME RST_PLTRST_N
J 0
(-7035 560);
DISPLAY 0.617021 (-7035 560);
PAINT ORANGE (-7035 560);
WIRE 16 -1 (-6975 1675)(-7750 1675);
FORCEPROP 2 LAST SIG_NAME XTAL_25MHZ_IN
J 0
(-7735 1685);
DISPLAY 0.617021 (-7735 1685);
PAINT ORANGE (-7735 1685);
FORCEPROP 2 LASTPROP $XRERR UNIQUE?
J 0
(-7975 1685);
DISPLAY 0.638298 (-7975 1685);
PAINT MONO (-7975 1685);
DISPLAY INVISIBLE (-7975 1685);
WIRE 16 -1 (-7750 1675)(-7750 1475);
WIRE 16 -1 (-7750 1475)(-7625 1475);
WIRE 16 -1 (-7750 1475)(-7750 1375);
WIRE 16 -1 (-7325 1575)(-6975 1575);
WIRE 16 -1 (-7325 1475)(-7325 1575);
FORCEPROP 2 LAST SIG_NAME XTAL_25MHZ_OUT_R
J 0
(-7335 1585);
DISPLAY 0.617021 (-7335 1585);
PAINT ORANGE (-7335 1585);
FORCEPROP 2 LASTPROP $XRERR UNIQUE?
J 0
(-7575 1585);
DISPLAY 0.638298 (-7575 1585);
PAINT MONO (-7575 1585);
DISPLAY INVISIBLE (-7575 1585);
WIRE 16 -1 (-7325 1375)(-7325 1475);
WIRE 16 -1 (-7325 1475)(-7425 1475);
DOT 1 (-6075 3775);
DOT 1 (-6725 3900);
DOT 1 (-7750 1475);
DOT 1 (-7325 1475);
DOT 1 (-6350 550);
DOT 1 (-7525 3325);
DOT 1 (-7275 3325);
DOT 1 (-6450 3525);
DOT 1 (-6450 3575);
DOT 1 (-6450 3675);
DOT 1 (-6450 3625);
DOT 1 (-5275 675);
DOT 1 (-5275 1050);
DOT 1 (-5025 675);
DOT 1 (-4775 675);
DOT 1 (-4525 675);
DOT 1 (-4275 675);
DOT 1 (-5025 1050);
DOT 1 (-4775 1050);
DOT 1 (-4525 1050);
DOT 1 (-4275 1050);
DOT 1 (-6075 3875);
DOT 1 (-6075 3925);
DOT 1 (-5250 3525);
DOT 1 (-6325 4150);
DOT 1 (-5725 4125);
DOT 1 (-5725 4175);
DOT 1 (-5725 4225);
DOT 1 (-5725 4275);
DOT 1 (-5725 4425);
DOT 1 (-3575 675);
DOT 1 (-3325 675);
DOT 1 (-3075 675);
DOT 1 (-3575 1050);
DOT 1 (-3325 1050);
DOT 1 (-3075 1050);
DOT 1 (-2825 675);
DOT 1 (-2575 675);
DOT 1 (-2825 1050);
DOT 1 (-2575 1050);
DOT 1 (-1925 675);
DOT 1 (-1600 675);
DOT 1 (-1350 675);
DOT 1 (-1100 675);
DOT 1 (-1925 1050);
DOT 1 (-1600 1050);
DOT 1 (-1350 1050);
DOT 1 (-1100 1050);
DOT 1 (-850 675);
DOT 1 (-600 675);
DOT 1 (-850 1050);
DOT 1 (-600 1050);
FORCENOTE
ROOM INTEL_SI
(-7875 300) 0;
DISPLAY LEFT (-7875 300);
DISPLAY 1.212766 (-7875 300);
PAINT PURPLE (-7875 300);
FORCENOTE
ROOM NT_FABRIC
(-7875 225) 0;
DISPLAY LEFT (-7875 225);
DISPLAY 1.212766 (-7875 225);
PAINT PURPLE (-7875 225);
QUIT
